(kicad_sch
	(version 20250114)
	(generator "eeschema")
	(generator_version "9.0")
	(paper "A3")
	(title_block
		(title "LPDDR4 Test Board")
		(date "2024-02-12")
		(rev "1.1.5")
	)
	(text "Master SPI Quad (x4) configuration scheme"
		(exclude_from_sim no)
		(at 24.13 24.765 0)
		(effects
			(font
				(size 2.9972 2.9972)
				(thickness 0.5994)
				(bold yes)
			)
			(justify left bottom)
		)
	)
	(text "(Q)SPI flash"
		(exclude_from_sim no)
		(at 61.595 80.645 0)
		(effects
			(font
				(size 2.9972 2.9972)
				(thickness 0.5994)
				(bold yes)
			)
			(justify left bottom)
		)
	)
	(text "STATUS LEDs"
		(exclude_from_sim no)
		(at 120.015 219.075 0)
		(effects
			(font
				(size 2.9972 2.9972)
				(thickness 0.5994)
				(bold yes)
			)
			(justify left bottom)
		)
	)
	(text "Follows Figure 2-14 7 Series FPGAs Configuration User Guide\nUG470 (v1.13.1)"
		(exclude_from_sim no)
		(at 24.765 32.385 0)
		(effects
			(font
				(size 2.0066 2.0066)
			)
			(justify left bottom)
		)
	)
	(text "MODE[2:0]\n000\n001\n010\n100\n101\n110\n111"
		(exclude_from_sim no)
		(at 265.43 240.665 0)
		(effects
			(font
				(size 1.27 1.27)
			)
			(justify left bottom)
		)
	)
	(text "For details, see UG470 p. 21"
		(exclude_from_sim no)
		(at 200.66 218.44 0)
		(effects
			(font
				(size 1.27 1.27)
			)
			(justify left bottom)
		)
	)
	(text "Compatible with Xilinx Platform Cable"
		(exclude_from_sim no)
		(at 31.75 218.44 0)
		(effects
			(font
				(size 1.27 1.27)
			)
			(justify left bottom)
		)
	)
	(text "Config. mode\nMaster Serial\nMaster SPI\nMaster BPI\nMaster SelectMAP\nJTAG\nSlave SelectMAP\nSlave Serial"
		(exclude_from_sim no)
		(at 246.38 240.665 0)
		(effects
			(font
				(size 1.27 1.27)
			)
			(justify left bottom)
		)
	)
	(text "JTAG Connector\n"
		(exclude_from_sim no)
		(at 31.115 215.9 0)
		(effects
			(font
				(size 2.9972 2.9972)
				(thickness 0.5994)
				(bold yes)
			)
			(justify left bottom)
		)
	)
	(text "Configuration Modes"
		(exclude_from_sim no)
		(at 200.025 215.265 0)
		(effects
			(font
				(size 2.9972 2.9972)
				(thickness 0.5994)
				(bold yes)
			)
			(justify left bottom)
		)
	)
	(text "FPGA BANK 0"
		(exclude_from_sim no)
		(at 317.5 68.58 0)
		(effects
			(font
				(size 2.9972 2.9972)
				(thickness 0.5994)
				(bold yes)
			)
			(justify left bottom)
		)
	)
	(junction
		(at 48.26 102.235)
		(diameter 0)
		(color 0 0 0 0)
	)
	(junction
		(at 317.5 146.685)
		(diameter 0)
		(color 0 0 0 0)
	)
	(junction
		(at 29.845 248.92)
		(diameter 0)
		(color 0 0 0 0)
	)
	(junction
		(at 106.68 112.395)
		(diameter 0)
		(color 0 0 0 0)
	)
	(junction
		(at 99.695 109.855)
		(diameter 0)
		(color 0 0 0 0)
	)
	(junction
		(at 217.17 227.965)
		(diameter 0)
		(color 0 0 0 0)
	)
	(junction
		(at 99.695 86.995)
		(diameter 0)
		(color 0 0 0 0)
	)
	(junction
		(at 288.925 128.905)
		(diameter 0)
		(color 0 0 0 0)
	)
	(junction
		(at 86.36 86.995)
		(diameter 0)
		(color 0 0 0 0)
	)
	(junction
		(at 29.845 238.76)
		(diameter 0)
		(color 0 0 0 0)
	)
	(junction
		(at 46.99 241.3)
		(diameter 0)
		(color 0 0 0 0)
	)
	(junction
		(at 172.085 113.03)
		(diameter 0)
		(color 0 0 0 0)
	)
	(junction
		(at 29.845 241.3)
		(diameter 0)
		(color 0 0 0 0)
	)
	(junction
		(at 44.45 243.84)
		(diameter 0)
		(color 0 0 0 0)
	)
	(junction
		(at 317.5 149.225)
		(diameter 0)
		(color 0 0 0 0)
	)
	(junction
		(at 29.845 246.38)
		(diameter 0)
		(color 0 0 0 0)
	)
	(junction
		(at 86.36 102.235)
		(diameter 0)
		(color 0 0 0 0)
	)
	(junction
		(at 288.925 107.95)
		(diameter 0)
		(color 0 0 0 0)
	)
	(junction
		(at 317.5 133.985)
		(diameter 0)
		(color 0 0 0 0)
	)
	(junction
		(at 280.67 126.365)
		(diameter 0)
		(color 0 0 0 0)
	)
	(junction
		(at 92.71 104.775)
		(diameter 0)
		(color 0 0 0 0)
	)
	(junction
		(at 29.845 243.84)
		(diameter 0)
		(color 0 0 0 0)
	)
	(junction
		(at 297.815 123.825)
		(diameter 0)
		(color 0 0 0 0)
	)
	(junction
		(at 317.5 141.605)
		(diameter 0)
		(color 0 0 0 0)
	)
	(junction
		(at 317.5 154.305)
		(diameter 0)
		(color 0 0 0 0)
	)
	(junction
		(at 29.845 236.22)
		(diameter 0)
		(color 0 0 0 0)
	)
	(junction
		(at 92.71 86.995)
		(diameter 0)
		(color 0 0 0 0)
	)
	(junction
		(at 48.26 120.015)
		(diameter 0)
		(color 0 0 0 0)
	)
	(junction
		(at 217.17 245.11)
		(diameter 0)
		(color 0 0 0 0)
	)
	(junction
		(at 49.53 238.76)
		(diameter 0)
		(color 0 0 0 0)
	)
	(junction
		(at 317.5 156.845)
		(diameter 0)
		(color 0 0 0 0)
	)
	(junction
		(at 52.07 236.22)
		(diameter 0)
		(color 0 0 0 0)
	)
	(no_connect
		(at 54.61 259.08)
	)
	(no_connect
		(at 71.12 114.935)
	)
	(no_connect
		(at 54.61 261.62)
	)
	(no_connect
		(at 41.91 248.92)
	)
	(no_connect
		(at 41.91 246.38)
	)
	(wire
		(pts
			(xy 109.22 117.475) (xy 80.01 117.475)
		)
		(stroke
			(width 0)
			(type default)
		)
	)
	(wire
		(pts
			(xy 320.04 100.965) (xy 314.325 100.965)
		)
		(stroke
			(width 0)
			(type default)
		)
	)
	(wire
		(pts
			(xy 297.815 107.95) (xy 288.925 107.95)
		)
		(stroke
			(width 0)
			(type default)
		)
	)
	(wire
		(pts
			(xy 31.75 241.3) (xy 29.845 241.3)
		)
		(stroke
			(width 0)
			(type default)
		)
	)
	(wire
		(pts
			(xy 99.695 86.995) (xy 99.695 89.535)
		)
		(stroke
			(width 0)
			(type default)
		)
	)
	(wire
		(pts
			(xy 213.36 266.065) (xy 219.71 266.065)
		)
		(stroke
			(width 0)
			(type default)
		)
	)
	(wire
		(pts
			(xy 262.255 126.365) (xy 280.67 126.365)
		)
		(stroke
			(width 0)
			(type default)
		)
	)
	(wire
		(pts
			(xy 71.12 102.235) (xy 74.93 102.235)
		)
		(stroke
			(width 0)
			(type default)
		)
	)
	(wire
		(pts
			(xy 320.04 149.225) (xy 317.5 149.225)
		)
		(stroke
			(width 0)
			(type default)
		)
	)
	(wire
		(pts
			(xy 52.07 274.32) (xy 54.61 274.32)
		)
		(stroke
			(width 0)
			(type default)
		)
	)
	(wire
		(pts
			(xy 86.36 94.615) (xy 86.36 102.235)
		)
		(stroke
			(width 0)
			(type default)
		)
	)
	(wire
		(pts
			(xy 194.945 113.03) (xy 197.485 113.03)
		)
		(stroke
			(width 0)
			(type default)
		)
	)
	(wire
		(pts
			(xy 217.17 233.045) (xy 220.98 233.045)
		)
		(stroke
			(width 0)
			(type default)
		)
	)
	(wire
		(pts
			(xy 317.5 154.305) (xy 317.5 156.845)
		)
		(stroke
			(width 0)
			(type default)
		)
	)
	(wire
		(pts
			(xy 92.71 99.695) (xy 92.71 104.775)
		)
		(stroke
			(width 0)
			(type default)
		)
	)
	(wire
		(pts
			(xy 48.26 102.235) (xy 52.07 102.235)
		)
		(stroke
			(width 0)
			(type default)
		)
	)
	(wire
		(pts
			(xy 280.67 107.95) (xy 288.925 107.95)
		)
		(stroke
			(width 0)
			(type default)
		)
	)
	(wire
		(pts
			(xy 71.12 112.395) (xy 74.93 112.395)
		)
		(stroke
			(width 0)
			(type default)
		)
	)
	(wire
		(pts
			(xy 126.365 234.95) (xy 133.985 234.95)
		)
		(stroke
			(width 0)
			(type default)
		)
	)
	(wire
		(pts
			(xy 288.925 128.905) (xy 262.255 128.905)
		)
		(stroke
			(width 0)
			(type default)
		)
	)
	(wire
		(pts
			(xy 49.53 254) (xy 49.53 238.76)
		)
		(stroke
			(width 0)
			(type default)
		)
	)
	(wire
		(pts
			(xy 317.5 141.605) (xy 317.5 146.685)
		)
		(stroke
			(width 0)
			(type default)
		)
	)
	(wire
		(pts
			(xy 153.67 262.255) (xy 153.67 264.795)
		)
		(stroke
			(width 0)
			(type default)
		)
	)
	(wire
		(pts
			(xy 172.085 102.87) (xy 172.085 105.41)
		)
		(stroke
			(width 0)
			(type default)
		)
	)
	(wire
		(pts
			(xy 52.07 236.22) (xy 54.61 236.22)
		)
		(stroke
			(width 0)
			(type default)
		)
	)
	(wire
		(pts
			(xy 217.17 271.145) (xy 217.17 268.605)
		)
		(stroke
			(width 0)
			(type default)
		)
	)
	(wire
		(pts
			(xy 29.845 233.68) (xy 29.845 236.22)
		)
		(stroke
			(width 0)
			(type default)
		)
	)
	(wire
		(pts
			(xy 29.845 238.76) (xy 29.845 241.3)
		)
		(stroke
			(width 0)
			(type default)
		)
	)
	(wire
		(pts
			(xy 44.45 269.24) (xy 44.45 243.84)
		)
		(stroke
			(width 0)
			(type default)
		)
	)
	(wire
		(pts
			(xy 297.815 113.03) (xy 297.815 107.95)
		)
		(stroke
			(width 0)
			(type default)
		)
	)
	(wire
		(pts
			(xy 217.17 250.19) (xy 217.17 245.11)
		)
		(stroke
			(width 0)
			(type default)
		)
	)
	(wire
		(pts
			(xy 153.67 264.795) (xy 151.13 264.795)
		)
		(stroke
			(width 0)
			(type default)
		)
	)
	(wire
		(pts
			(xy 99.695 86.995) (xy 106.68 86.995)
		)
		(stroke
			(width 0)
			(type default)
		)
	)
	(wire
		(pts
			(xy 46.99 241.3) (xy 54.61 241.3)
		)
		(stroke
			(width 0)
			(type default)
		)
	)
	(wire
		(pts
			(xy 48.26 99.695) (xy 48.26 102.235)
		)
		(stroke
			(width 0)
			(type default)
		)
	)
	(wire
		(pts
			(xy 80.01 112.395) (xy 106.68 112.395)
		)
		(stroke
			(width 0)
			(type default)
		)
	)
	(wire
		(pts
			(xy 169.545 113.03) (xy 172.085 113.03)
		)
		(stroke
			(width 0)
			(type default)
		)
	)
	(wire
		(pts
			(xy 41.91 243.84) (xy 44.45 243.84)
		)
		(stroke
			(width 0)
			(type default)
		)
	)
	(wire
		(pts
			(xy 172.085 113.03) (xy 172.085 115.57)
		)
		(stroke
			(width 0)
			(type default)
		)
	)
	(wire
		(pts
			(xy 41.91 236.22) (xy 52.07 236.22)
		)
		(stroke
			(width 0)
			(type default)
		)
	)
	(wire
		(pts
			(xy 92.71 104.775) (xy 92.71 121.285)
		)
		(stroke
			(width 0)
			(type default)
		)
	)
	(wire
		(pts
			(xy 320.04 116.205) (xy 314.325 116.205)
		)
		(stroke
			(width 0)
			(type default)
		)
	)
	(wire
		(pts
			(xy 217.17 227.965) (xy 220.98 227.965)
		)
		(stroke
			(width 0)
			(type default)
		)
	)
	(wire
		(pts
			(xy 86.36 86.995) (xy 86.36 89.535)
		)
		(stroke
			(width 0)
			(type default)
		)
	)
	(wire
		(pts
			(xy 80.01 120.015) (xy 109.22 120.015)
		)
		(stroke
			(width 0)
			(type default)
		)
	)
	(wire
		(pts
			(xy 153.035 245.11) (xy 150.495 245.11)
		)
		(stroke
			(width 0)
			(type default)
		)
	)
	(wire
		(pts
			(xy 228.6 251.46) (xy 228.6 250.19)
		)
		(stroke
			(width 0)
			(type default)
		)
	)
	(wire
		(pts
			(xy 46.99 266.7) (xy 46.99 241.3)
		)
		(stroke
			(width 0)
			(type default)
		)
	)
	(wire
		(pts
			(xy 320.04 106.045) (xy 314.325 106.045)
		)
		(stroke
			(width 0)
			(type default)
		)
	)
	(wire
		(pts
			(xy 153.035 242.57) (xy 153.035 245.11)
		)
		(stroke
			(width 0)
			(type default)
		)
	)
	(wire
		(pts
			(xy 29.845 246.38) (xy 29.845 248.92)
		)
		(stroke
			(width 0)
			(type default)
		)
	)
	(wire
		(pts
			(xy 86.36 102.235) (xy 109.22 102.235)
		)
		(stroke
			(width 0)
			(type default)
		)
	)
	(wire
		(pts
			(xy 41.91 233.68) (xy 46.99 233.68)
		)
		(stroke
			(width 0)
			(type default)
		)
	)
	(wire
		(pts
			(xy 48.26 113.665) (xy 48.26 120.015)
		)
		(stroke
			(width 0)
			(type default)
		)
	)
	(wire
		(pts
			(xy 46.99 233.68) (xy 46.99 231.14)
		)
		(stroke
			(width 0)
			(type default)
		)
	)
	(wire
		(pts
			(xy 48.26 120.015) (xy 48.26 122.555)
		)
		(stroke
			(width 0)
			(type default)
		)
	)
	(wire
		(pts
			(xy 320.04 98.425) (xy 314.325 98.425)
		)
		(stroke
			(width 0)
			(type default)
		)
	)
	(wire
		(pts
			(xy 172.085 120.65) (xy 172.085 123.19)
		)
		(stroke
			(width 0)
			(type default)
		)
	)
	(wire
		(pts
			(xy 317.5 85.725) (xy 317.5 88.265)
		)
		(stroke
			(width 0)
			(type default)
		)
	)
	(wire
		(pts
			(xy 31.75 248.92) (xy 29.845 248.92)
		)
		(stroke
			(width 0)
			(type default)
		)
	)
	(wire
		(pts
			(xy 317.5 146.685) (xy 320.04 146.685)
		)
		(stroke
			(width 0)
			(type default)
		)
	)
	(wire
		(pts
			(xy 288.925 131.445) (xy 288.925 128.905)
		)
		(stroke
			(width 0)
			(type default)
		)
	)
	(wire
		(pts
			(xy 228.6 233.045) (xy 226.06 233.045)
		)
		(stroke
			(width 0)
			(type default)
		)
	)
	(wire
		(pts
			(xy 106.68 99.695) (xy 106.68 112.395)
		)
		(stroke
			(width 0)
			(type default)
		)
	)
	(wire
		(pts
			(xy 29.845 236.22) (xy 29.845 238.76)
		)
		(stroke
			(width 0)
			(type default)
		)
	)
	(wire
		(pts
			(xy 31.75 243.84) (xy 29.845 243.84)
		)
		(stroke
			(width 0)
			(type default)
		)
	)
	(wire
		(pts
			(xy 160.02 257.175) (xy 160.02 254.635)
		)
		(stroke
			(width 0)
			(type default)
		)
	)
	(wire
		(pts
			(xy 320.04 139.065) (xy 317.5 139.065)
		)
		(stroke
			(width 0)
			(type default)
		)
	)
	(wire
		(pts
			(xy 127 254.635) (xy 134.62 254.635)
		)
		(stroke
			(width 0)
			(type default)
		)
	)
	(wire
		(pts
			(xy 320.04 141.605) (xy 317.5 141.605)
		)
		(stroke
			(width 0)
			(type default)
		)
	)
	(wire
		(pts
			(xy 31.75 236.22) (xy 29.845 236.22)
		)
		(stroke
			(width 0)
			(type default)
		)
	)
	(wire
		(pts
			(xy 144.145 234.95) (xy 139.065 234.95)
		)
		(stroke
			(width 0)
			(type default)
		)
	)
	(wire
		(pts
			(xy 288.925 128.905) (xy 320.04 128.905)
		)
		(stroke
			(width 0)
			(type default)
		)
	)
	(wire
		(pts
			(xy 48.26 102.235) (xy 48.26 108.585)
		)
		(stroke
			(width 0)
			(type default)
		)
	)
	(wire
		(pts
			(xy 261.62 123.825) (xy 297.815 123.825)
		)
		(stroke
			(width 0)
			(type default)
		)
	)
	(polyline
		(pts
			(xy 264.795 226.06) (xy 264.795 240.665)
		)
		(stroke
			(width 0.1016)
			(type solid)
		)
	)
	(wire
		(pts
			(xy 288.925 107.95) (xy 288.925 113.03)
		)
		(stroke
			(width 0)
			(type default)
		)
	)
	(wire
		(pts
			(xy 280.67 118.11) (xy 280.67 126.365)
		)
		(stroke
			(width 0)
			(type default)
		)
	)
	(wire
		(pts
			(xy 48.26 120.015) (xy 52.07 120.015)
		)
		(stroke
			(width 0)
			(type default)
		)
	)
	(wire
		(pts
			(xy 71.12 117.475) (xy 74.93 117.475)
		)
		(stroke
			(width 0)
			(type default)
		)
	)
	(wire
		(pts
			(xy 297.815 123.825) (xy 320.04 123.825)
		)
		(stroke
			(width 0)
			(type default)
		)
	)
	(wire
		(pts
			(xy 54.61 254) (xy 49.53 254)
		)
		(stroke
			(width 0)
			(type default)
		)
	)
	(wire
		(pts
			(xy 320.04 113.665) (xy 314.325 113.665)
		)
		(stroke
			(width 0)
			(type default)
		)
	)
	(wire
		(pts
			(xy 99.695 109.855) (xy 80.01 109.855)
		)
		(stroke
			(width 0)
			(type default)
		)
	)
	(wire
		(pts
			(xy 217.17 263.525) (xy 217.17 260.35)
		)
		(stroke
			(width 0)
			(type default)
		)
	)
	(wire
		(pts
			(xy 320.04 156.845) (xy 317.5 156.845)
		)
		(stroke
			(width 0)
			(type default)
		)
	)
	(wire
		(pts
			(xy 54.61 251.46) (xy 52.07 251.46)
		)
		(stroke
			(width 0)
			(type default)
		)
	)
	(wire
		(pts
			(xy 71.12 104.775) (xy 74.93 104.775)
		)
		(stroke
			(width 0)
			(type default)
		)
	)
	(wire
		(pts
			(xy 49.53 238.76) (xy 54.61 238.76)
		)
		(stroke
			(width 0)
			(type default)
		)
	)
	(wire
		(pts
			(xy 92.71 86.995) (xy 99.695 86.995)
		)
		(stroke
			(width 0)
			(type default)
		)
	)
	(wire
		(pts
			(xy 226.06 245.11) (xy 231.14 245.11)
		)
		(stroke
			(width 0)
			(type default)
		)
	)
	(wire
		(pts
			(xy 86.36 86.995) (xy 92.71 86.995)
		)
		(stroke
			(width 0)
			(type default)
		)
	)
	(wire
		(pts
			(xy 92.71 127.635) (xy 92.71 126.365)
		)
		(stroke
			(width 0)
			(type default)
		)
	)
	(wire
		(pts
			(xy 228.6 250.19) (xy 226.06 250.19)
		)
		(stroke
			(width 0)
			(type default)
		)
	)
	(wire
		(pts
			(xy 31.75 233.68) (xy 29.845 233.68)
		)
		(stroke
			(width 0)
			(type default)
		)
	)
	(wire
		(pts
			(xy 297.815 118.11) (xy 297.815 123.825)
		)
		(stroke
			(width 0)
			(type default)
		)
	)
	(wire
		(pts
			(xy 172.085 113.03) (xy 174.625 113.03)
		)
		(stroke
			(width 0)
			(type default)
		)
	)
	(wire
		(pts
			(xy 54.61 266.7) (xy 46.99 266.7)
		)
		(stroke
			(width 0)
			(type default)
		)
	)
	(wire
		(pts
			(xy 212.725 245.11) (xy 217.17 245.11)
		)
		(stroke
			(width 0)
			(type default)
		)
	)
	(wire
		(pts
			(xy 320.04 154.305) (xy 317.5 154.305)
		)
		(stroke
			(width 0)
			(type default)
		)
	)
	(wire
		(pts
			(xy 212.725 227.965) (xy 217.17 227.965)
		)
		(stroke
			(width 0)
			(type default)
		)
	)
	(wire
		(pts
			(xy 320.04 133.985) (xy 317.5 133.985)
		)
		(stroke
			(width 0)
			(type default)
		)
	)
	(wire
		(pts
			(xy 159.385 234.95) (xy 156.845 234.95)
		)
		(stroke
			(width 0)
			(type default)
		)
	)
	(wire
		(pts
			(xy 288.925 118.11) (xy 288.925 128.905)
		)
		(stroke
			(width 0)
			(type default)
		)
	)
	(wire
		(pts
			(xy 52.07 276.86) (xy 52.07 274.32)
		)
		(stroke
			(width 0)
			(type default)
		)
	)
	(wire
		(pts
			(xy 29.845 243.84) (xy 29.845 246.38)
		)
		(stroke
			(width 0)
			(type default)
		)
	)
	(wire
		(pts
			(xy 41.91 238.76) (xy 49.53 238.76)
		)
		(stroke
			(width 0)
			(type default)
		)
	)
	(wire
		(pts
			(xy 320.04 118.745) (xy 314.325 118.745)
		)
		(stroke
			(width 0)
			(type default)
		)
	)
	(wire
		(pts
			(xy 226.06 227.965) (xy 231.14 227.965)
		)
		(stroke
			(width 0)
			(type default)
		)
	)
	(wire
		(pts
			(xy 116.84 254.635) (xy 119.38 254.635)
		)
		(stroke
			(width 0)
			(type default)
		)
	)
	(wire
		(pts
			(xy 80.01 104.775) (xy 92.71 104.775)
		)
		(stroke
			(width 0)
			(type default)
		)
	)
	(polyline
		(pts
			(xy 245.745 226.06) (xy 275.59 226.06)
		)
		(stroke
			(width 0.1016)
			(type solid)
		)
	)
	(wire
		(pts
			(xy 31.75 238.76) (xy 29.845 238.76)
		)
		(stroke
			(width 0)
			(type default)
		)
	)
	(wire
		(pts
			(xy 280.67 113.03) (xy 280.67 107.95)
		)
		(stroke
			(width 0)
			(type default)
		)
	)
	(wire
		(pts
			(xy 314.325 111.125) (xy 320.04 111.125)
		)
		(stroke
			(width 0)
			(type default)
		)
	)
	(wire
		(pts
			(xy 41.91 241.3) (xy 46.99 241.3)
		)
		(stroke
			(width 0)
			(type default)
		)
	)
	(wire
		(pts
			(xy 217.17 233.045) (xy 217.17 227.965)
		)
		(stroke
			(width 0)
			(type default)
		)
	)
	(wire
		(pts
			(xy 44.45 243.84) (xy 54.61 243.84)
		)
		(stroke
			(width 0)
			(type default)
		)
	)
	(wire
		(pts
			(xy 71.12 109.855) (xy 74.93 109.855)
		)
		(stroke
			(width 0)
			(type default)
		)
	)
	(wire
		(pts
			(xy 83.82 86.995) (xy 86.36 86.995)
		)
		(stroke
			(width 0)
			(type default)
		)
	)
	(wire
		(pts
			(xy 317.5 93.345) (xy 317.5 133.985)
		)
		(stroke
			(width 0)
			(type default)
		)
	)
	(wire
		(pts
			(xy 144.78 254.635) (xy 139.7 254.635)
		)
		(stroke
			(width 0)
			(type default)
		)
	)
	(wire
		(pts
			(xy 280.67 126.365) (xy 320.04 126.365)
		)
		(stroke
			(width 0)
			(type default)
		)
	)
	(wire
		(pts
			(xy 106.68 112.395) (xy 109.22 112.395)
		)
		(stroke
			(width 0)
			(type default)
		)
	)
	(wire
		(pts
			(xy 52.07 251.46) (xy 52.07 236.22)
		)
		(stroke
			(width 0)
			(type default)
		)
	)
	(wire
		(pts
			(xy 228.6 234.315) (xy 228.6 233.045)
		)
		(stroke
			(width 0)
			(type default)
		)
	)
	(wire
		(pts
			(xy 317.5 154.305) (xy 317.5 149.225)
		)
		(stroke
			(width 0)
			(type default)
		)
	)
	(wire
		(pts
			(xy 29.845 241.3) (xy 29.845 243.84)
		)
		(stroke
			(width 0)
			(type default)
		)
	)
	(wire
		(pts
			(xy 71.12 120.015) (xy 74.93 120.015)
		)
		(stroke
			(width 0)
			(type default)
		)
	)
	(wire
		(pts
			(xy 106.68 86.995) (xy 106.68 94.615)
		)
		(stroke
			(width 0)
			(type default)
		)
	)
	(wire
		(pts
			(xy 217.17 263.525) (xy 219.71 263.525)
		)
		(stroke
			(width 0)
			(type default)
		)
	)
	(wire
		(pts
			(xy 217.17 245.11) (xy 220.98 245.11)
		)
		(stroke
			(width 0)
			(type default)
		)
	)
	(wire
		(pts
			(xy 317.5 146.685) (xy 317.5 149.225)
		)
		(stroke
			(width 0)
			(type default)
		)
	)
	(wire
		(pts
			(xy 288.925 104.14) (xy 288.925 107.95)
		)
		(stroke
			(width 0)
			(type default)
		)
	)
	(wire
		(pts
			(xy 99.695 109.855) (xy 109.22 109.855)
		)
		(stroke
			(width 0)
			(type default)
		)
	)
	(wire
		(pts
			(xy 29.845 248.92) (xy 29.845 253.365)
		)
		(stroke
			(width 0)
			(type default)
		)
	)
	(wire
		(pts
			(xy 320.04 103.505) (xy 314.325 103.505)
		)
		(stroke
			(width 0)
			(type default)
		)
	)
	(wire
		(pts
			(xy 217.17 268.605) (xy 219.71 268.605)
		)
		(stroke
			(width 0)
			(type default)
		)
	)
	(wire
		(pts
			(xy 92.71 86.995) (xy 92.71 94.615)
		)
		(stroke
			(width 0)
			(type default)
		)
	)
	(wire
		(pts
			(xy 317.5 156.845) (xy 317.5 159.385)
		)
		(stroke
			(width 0)
			(type default)
		)
	)
	(wire
		(pts
			(xy 217.17 260.35) (xy 231.775 260.35)
		)
		(stroke
			(width 0)
			(type default)
		)
	)
	(wire
		(pts
			(xy 217.17 250.19) (xy 220.98 250.19)
		)
		(stroke
			(width 0)
			(type default)
		)
	)
	(wire
		(pts
			(xy 99.695 109.855) (xy 99.695 94.615)
		)
		(stroke
			(width 0)
			(type default)
		)
	)
	(wire
		(pts
			(xy 54.61 269.24) (xy 44.45 269.24)
		)
		(stroke
			(width 0)
			(type default)
		)
	)
	(wire
		(pts
			(xy 314.96 133.985) (xy 317.5 133.985)
		)
		(stroke
			(width 0)
			(type default)
		)
	)
	(wire
		(pts
			(xy 116.205 234.95) (xy 118.745 234.95)
		)
		(stroke
			(width 0)
			(type default)
		)
	)
	(wire
		(pts
			(xy 80.01 102.235) (xy 86.36 102.235)
		)
		(stroke
			(width 0)
			(type default)
		)
	)
	(wire
		(pts
			(xy 172.085 110.49) (xy 172.085 113.03)
		)
		(stroke
			(width 0)
			(type default)
		)
	)
	(wire
		(pts
			(xy 31.75 246.38) (xy 29.845 246.38)
		)
		(stroke
			(width 0)
			(type default)
		)
	)
	(wire
		(pts
			(xy 288.925 141.605) (xy 288.925 144.145)
		)
		(stroke
			(width 0)
			(type default)
		)
	)
	(wire
		(pts
			(xy 159.385 237.49) (xy 159.385 234.95)
		)
		(stroke
			(width 0)
			(type default)
		)
	)
	(wire
		(pts
			(xy 160.02 254.635) (xy 157.48 254.635)
		)
		(stroke
			(width 0)
			(type default)
		)
	)
	(wire
		(pts
			(xy 317.5 139.065) (xy 317.5 141.605)
		)
		(stroke
			(width 0)
			(type default)
		)
	)
	(wire
		(pts
			(xy 92.71 104.775) (xy 109.22 104.775)
		)
		(stroke
			(width 0)
			(type default)
		)
	)
	(global_label "EMCCLK"
		(shape input)
		(at 197.485 113.03 0)
		(fields_autoplaced yes)
		(effects
			(font
				(size 1.27 1.27)
			)
			(justify left)
		)
		(property "Intersheetrefs" "${INTERSHEET_REFS}"
			(at -5.08 -47.625 0)
			(effects
				(font
					(size 1.27 1.27)
				)
				(hide yes)
			)
		)
	)
	(global_label "TMS_JTAG"
		(shape input)
		(at 54.61 236.22 0)
		(fields_autoplaced yes)
		(effects
			(font
				(size 1.27 1.27)
			)
			(justify left)
		)
		(property "Intersheetrefs" "${INTERSHEET_REFS}"
			(at -10.795 -4.445 0)
			(effects
				(font
					(size 1.27 1.27)
				)
				(hide yes)
			)
		)
	)
	(global_label "3V3_SYS"
		(shape input)
		(at 231.14 227.965 0)
		(fields_autoplaced yes)
		(effects
			(font
				(size 1.27 1.27)
			)
			(justify left)
		)
		(property "Intersheetrefs" "${INTERSHEET_REFS}"
			(at 241.4538 227.965 0)
			(effects
				(font
					(size 1.27 1.27)
				)
				(justify left)
				(hide yes)
			)
		)
	)
	(global_label "MODE0"
		(shape input)
		(at 212.725 227.965 180)
		(fields_autoplaced yes)
		(effects
			(font
				(size 1.27 1.27)
			)
			(justify right)
		)
		(property "Intersheetrefs" "${INTERSHEET_REFS}"
			(at 203.9836 227.965 0)
			(effects
				(font
					(size 1.27 1.27)
				)
				(justify right)
				(hide yes)
			)
		)
	)
	(global_label "TDI_JTAG"
		(shape input)
		(at 314.325 98.425 180)
		(fields_autoplaced yes)
		(effects
			(font
				(size 1.27 1.27)
			)
			(justify right)
		)
		(property "Intersheetrefs" "${INTERSHEET_REFS}"
			(at 36.195 -15.875 0)
			(effects
				(font
					(size 1.27 1.27)
				)
				(hide yes)
			)
		)
	)
	(global_label "3V3_SYS"
		(shape input)
		(at 231.775 260.35 0)
		(fields_autoplaced yes)
		(effects
			(font
				(size 1.27 1.27)
			)
			(justify left)
		)
		(property "Intersheetrefs" "${INTERSHEET_REFS}"
			(at 0 10.795 0)
			(effects
				(font
					(size 1.27 1.27)
				)
				(hide yes)
			)
		)
	)
	(global_label "3V3_SYS"
		(shape input)
		(at 116.84 254.635 180)
		(fields_autoplaced yes)
		(effects
			(font
				(size 1.27 1.27)
			)
			(justify right)
		)
		(property "Intersheetrefs" "${INTERSHEET_REFS}"
			(at -8.89 -4.445 0)
			(effects
				(font
					(size 1.27 1.27)
				)
				(hide yes)
			)
		)
	)
	(global_label "TDO_JTAG"
		(shape input)
		(at 314.325 100.965 180)
		(fields_autoplaced yes)
		(effects
			(font
				(size 1.27 1.27)
			)
			(justify right)
		)
		(property "Intersheetrefs" "${INTERSHEET_REFS}"
			(at 36.195 -15.875 0)
			(effects
				(font
					(size 1.27 1.27)
				)
				(hide yes)
			)
		)
	)
	(global_label "DONE"
		(shape input)
		(at 261.62 123.825 180)
		(fields_autoplaced yes)
		(effects
			(font
				(size 1.27 1.27)
			)
			(justify right)
		)
		(property "Intersheetrefs" "${INTERSHEET_REFS}"
			(at 40.005 -15.875 0)
			(effects
				(font
					(size 1.27 1.27)
				)
				(hide yes)
			)
		)
	)
	(global_label "MODE1"
		(shape input)
		(at 212.725 245.11 180)
		(fields_autoplaced yes)
		(effects
			(font
				(size 1.27 1.27)
			)
			(justify right)
		)
		(property "Intersheetrefs" "${INTERSHEET_REFS}"
			(at 0 4.445 0)
			(effects
				(font
					(size 1.27 1.27)
				)
				(hide yes)
			)
		)
	)
	(global_label "TDI_JTAG"
		(shape input)
		(at 54.61 243.84 0)
		(fields_autoplaced yes)
		(effects
			(font
				(size 1.27 1.27)
			)
			(justify left)
		)
		(property "Intersheetrefs" "${INTERSHEET_REFS}"
			(at -10.795 -4.445 0)
			(effects
				(font
					(size 1.27 1.27)
				)
				(hide yes)
			)
		)
	)
	(global_label "CCLK"
		(shape input)
		(at 314.325 111.125 180)
		(fields_autoplaced yes)
		(effects
			(font
				(size 1.27 1.27)
			)
			(justify right)
		)
		(property "Intersheetrefs" "${INTERSHEET_REFS}"
			(at 36.195 -15.875 0)
			(effects
				(font
					(size 1.27 1.27)
				)
				(hide yes)
			)
		)
	)
	(global_label "CFGBVS"
		(shape input)
		(at 314.96 133.985 180)
		(fields_autoplaced yes)
		(effects
			(font
				(size 1.27 1.27)
			)
			(justify right)
		)
		(property "Intersheetrefs" "${INTERSHEET_REFS}"
			(at 36.195 -15.875 0)
			(effects
				(font
					(size 1.27 1.27)
				)
				(hide yes)
			)
		)
	)
	(global_label "TCK_JTAG"
		(shape input)
		(at 314.325 106.045 180)
		(fields_autoplaced yes)
		(effects
			(font
				(size 1.27 1.27)
			)
			(justify right)
		)
		(property "Intersheetrefs" "${INTERSHEET_REFS}"
			(at 36.195 -15.875 0)
			(effects
				(font
					(size 1.27 1.27)
				)
				(hide yes)
			)
		)
	)
	(global_label "PROGRAM_B"
		(shape input)
		(at 262.255 128.905 180)
		(fields_autoplaced yes)
		(effects
			(font
				(size 1.27 1.27)
			)
			(justify right)
		)
		(property "Intersheetrefs" "${INTERSHEET_REFS}"
			(at 40.005 -15.875 0)
			(effects
				(font
					(size 1.27 1.27)
				)
				(hide yes)
			)
		)
	)
	(global_label "3V3_SYS"
		(shape input)
		(at 288.925 104.14 90)
		(fields_autoplaced yes)
		(effects
			(font
				(size 1.27 1.27)
			)
			(justify left)
		)
		(property "Intersheetrefs" "${INTERSHEET_REFS}"
			(at 40.005 -15.875 0)
			(effects
				(font
					(size 1.27 1.27)
				)
				(hide yes)
			)
		)
	)
	(global_label "PUDC_B"
		(shape input)
		(at 174.625 113.03 0)
		(fields_autoplaced yes)
		(effects
			(font
				(size 1.27 1.27)
			)
			(justify left)
		)
		(property "Intersheetrefs" "${INTERSHEET_REFS}"
			(at 10.16 -47.625 0)
			(effects
				(font
					(size 1.27 1.27)
				)
				(hide yes)
			)
		)
	)
	(global_label "QSPI_DQ3"
		(shape input)
		(at 109.22 109.855 0)
		(fields_autoplaced yes)
		(effects
			(font
				(size 1.27 1.27)
			)
			(justify left)
		)
		(property "Intersheetrefs" "${INTERSHEET_REFS}"
			(at -48.895 -3.175 0)
			(effects
				(font
					(size 1.27 1.27)
				)
				(hide yes)
			)
		)
	)
	(global_label "INIT_B"
		(shape input)
		(at 262.255 126.365 180)
		(fields_autoplaced yes)
		(effects
			(font
				(size 1.27 1.27)
			)
			(justify right)
		)
		(property "Intersheetrefs" "${INTERSHEET_REFS}"
			(at 40.005 -15.875 0)
			(effects
				(font
					(size 1.27 1.27)
				)
				(hide yes)
			)
		)
	)
	(global_label "3V3_SYS"
		(shape input)
		(at 83.82 86.995 180)
		(fields_autoplaced yes)
		(effects
			(font
				(size 1.27 1.27)
			)
			(justify right)
		)
		(property "Intersheetrefs" "${INTERSHEET_REFS}"
			(at 3.81 231.775 0)
			(effects
				(font
					(size 1.27 1.27)
				)
				(hide yes)
			)
		)
	)
	(global_label "QSPI_DQ2"
		(shape input)
		(at 109.22 112.395 0)
		(fields_autoplaced yes)
		(effects
			(font
				(size 1.27 1.27)
			)
			(justify left)
		)
		(property "Intersheetrefs" "${INTERSHEET_REFS}"
			(at -48.895 -3.175 0)
			(effects
				(font
					(size 1.27 1.27)
				)
				(hide yes)
			)
		)
	)
	(global_label "TDO_JTAG"
		(shape input)
		(at 54.61 241.3 0)
		(fields_autoplaced yes)
		(effects
			(font
				(size 1.27 1.27)
			)
			(justify left)
		)
		(property "Intersheetrefs" "${INTERSHEET_REFS}"
			(at -10.795 -4.445 0)
			(effects
				(font
					(size 1.27 1.27)
				)
				(hide yes)
			)
		)
	)
	(global_label "QSPI_DQ0"
		(shape input)
		(at 109.22 117.475 0)
		(fields_autoplaced yes)
		(effects
			(font
				(size 1.27 1.27)
			)
			(justify left)
		)
		(property "Intersheetrefs" "${INTERSHEET_REFS}"
			(at -48.895 -3.175 0)
			(effects
				(font
					(size 1.27 1.27)
				)
				(hide yes)
			)
		)
	)
	(global_label "3V3_SYS"
		(shape input)
		(at 172.085 102.87 90)
		(fields_autoplaced yes)
		(effects
			(font
				(size 1.27 1.27)
			)
			(justify left)
		)
		(property "Intersheetrefs" "${INTERSHEET_REFS}"
			(at 15.24 -43.18 0)
			(effects
				(font
					(size 1.27 1.27)
				)
				(hide yes)
			)
		)
	)
	(global_label "FCS_B"
		(shape input)
		(at 109.22 102.235 0)
		(fields_autoplaced yes)
		(effects
			(font
				(size 1.27 1.27)
			)
			(justify left)
		)
		(property "Intersheetrefs" "${INTERSHEET_REFS}"
			(at -49.53 -3.175 0)
			(effects
				(font
					(size 1.27 1.27)
				)
				(hide yes)
			)
		)
	)
	(global_label "MODE0"
		(shape input)
		(at 314.325 113.665 180)
		(fields_autoplaced yes)
		(effects
			(font
				(size 1.27 1.27)
			)
			(justify right)
		)
		(property "Intersheetrefs" "${INTERSHEET_REFS}"
			(at 36.195 -15.875 0)
			(effects
				(font
					(size 1.27 1.27)
				)
				(hide yes)
			)
		)
	)
	(global_label "MODE2"
		(shape input)
		(at 314.325 118.745 180)
		(fields_autoplaced yes)
		(effects
			(font
				(size 1.27 1.27)
			)
			(justify right)
		)
		(property "Intersheetrefs" "${INTERSHEET_REFS}"
			(at 36.195 -15.875 0)
			(effects
				(font
					(size 1.27 1.27)
				)
				(hide yes)
			)
		)
	)
	(global_label "MODE2"
		(shape input)
		(at 213.36 266.065 180)
		(fields_autoplaced yes)
		(effects
			(font
				(size 1.27 1.27)
			)
			(justify right)
		)
		(property "Intersheetrefs" "${INTERSHEET_REFS}"
			(at 0 10.795 0)
			(effects
				(font
					(size 1.27 1.27)
				)
				(hide yes)
			)
		)
	)
	(global_label "3V3_SYS"
		(shape input)
		(at 46.99 231.14 90)
		(fields_autoplaced yes)
		(effects
			(font
				(size 1.27 1.27)
			)
			(justify left)
		)
		(property "Intersheetrefs" "${INTERSHEET_REFS}"
			(at 5.715 -2.54 0)
			(effects
				(font
					(size 1.27 1.27)
				)
				(hide yes)
			)
		)
	)
	(global_label "TMS_JTAG"
		(shape input)
		(at 314.325 103.505 180)
		(fields_autoplaced yes)
		(effects
			(font
				(size 1.27 1.27)
			)
			(justify right)
		)
		(property "Intersheetrefs" "${INTERSHEET_REFS}"
			(at 36.195 -15.875 0)
			(effects
				(font
					(size 1.27 1.27)
				)
				(hide yes)
			)
		)
	)
	(global_label "QSPI_DQ1"
		(shape input)
		(at 109.22 120.015 0)
		(fields_autoplaced yes)
		(effects
			(font
				(size 1.27 1.27)
			)
			(justify left)
		)
		(property "Intersheetrefs" "${INTERSHEET_REFS}"
			(at -48.895 -3.175 0)
			(effects
				(font
					(size 1.27 1.27)
				)
				(hide yes)
			)
		)
	)
	(global_label "3V3_SYS"
		(shape input)
		(at 231.14 245.11 0)
		(fields_autoplaced yes)
		(effects
			(font
				(size 1.27 1.27)
			)
			(justify left)
		)
		(property "Intersheetrefs" "${INTERSHEET_REFS}"
			(at 0 4.445 0)
			(effects
				(font
					(size 1.27 1.27)
				)
				(hide yes)
			)
		)
	)
	(global_label "3V3_SYS"
		(shape input)
		(at 48.26 99.695 90)
		(fields_autoplaced yes)
		(effects
			(font
				(size 1.27 1.27)
			)
			(justify left)
		)
		(property "Intersheetrefs" "${INTERSHEET_REFS}"
			(at -21.59 -0.635 0)
			(effects
				(font
					(size 1.27 1.27)
				)
				(hide yes)
			)
		)
	)
	(global_label "3V3_SYS"
		(shape input)
		(at 116.205 234.95 180)
		(fields_autoplaced yes)
		(effects
			(font
				(size 1.27 1.27)
			)
			(justify right)
		)
		(property "Intersheetrefs" "${INTERSHEET_REFS}"
			(at -8.89 -4.445 0)
			(effects
				(font
					(size 1.27 1.27)
				)
				(hide yes)
			)
		)
	)
	(global_label "INIT_B"
		(shape input)
		(at 151.13 264.795 180)
		(fields_autoplaced yes)
		(effects
			(font
				(size 1.27 1.27)
			)
			(justify right)
		)
		(property "Intersheetrefs" "${INTERSHEET_REFS}"
			(at 22.86 -1.905 0)
			(effects
				(font
					(size 1.27 1.27)
				)
				(hide yes)
			)
		)
	)
	(global_label "TCK_JTAG"
		(shape input)
		(at 54.61 238.76 0)
		(fields_autoplaced yes)
		(effects
			(font
				(size 1.27 1.27)
			)
			(justify left)
		)
		(property "Intersheetrefs" "${INTERSHEET_REFS}"
			(at -10.795 -4.445 0)
			(effects
				(font
					(size 1.27 1.27)
				)
				(hide yes)
			)
		)
	)
	(global_label "DONE"
		(shape input)
		(at 150.495 245.11 180)
		(fields_autoplaced yes)
		(effects
			(font
				(size 1.27 1.27)
			)
			(justify right)
		)
		(property "Intersheetrefs" "${INTERSHEET_REFS}"
			(at 22.86 -1.905 0)
			(effects
				(font
					(size 1.27 1.27)
				)
				(hide yes)
			)
		)
	)
	(global_label "3V3_SYS"
		(shape input)
		(at 317.5 85.725 90)
		(fields_autoplaced yes)
		(effects
			(font
				(size 1.27 1.27)
			)
			(justify left)
		)
		(property "Intersheetrefs" "${INTERSHEET_REFS}"
			(at 27.305 -0.635 0)
			(effects
				(font
					(size 1.27 1.27)
				)
				(hide yes)
			)
		)
	)
	(global_label "CCLK"
		(shape input)
		(at 109.22 104.775 0)
		(fields_autoplaced yes)
		(effects
			(font
				(size 1.27 1.27)
			)
			(justify left)
		)
		(property "Intersheetrefs" "${INTERSHEET_REFS}"
			(at -49.53 -3.175 0)
			(effects
				(font
					(size 1.27 1.27)
				)
				(hide yes)
			)
		)
	)
	(global_label "MODE1"
		(shape input)
		(at 314.325 116.205 180)
		(fields_autoplaced yes)
		(effects
			(font
				(size 1.27 1.27)
			)
			(justify right)
		)
		(property "Intersheetrefs" "${INTERSHEET_REFS}"
			(at 36.195 -15.875 0)
			(effects
				(font
					(size 1.27 1.27)
				)
				(hide yes)
			)
		)
	)
	(symbol
		(lib_id "antmicropower:GND")
		(at 29.845 253.365 0)
		(unit 1)
		(exclude_from_sim no)
		(in_bom yes)
		(on_board yes)
		(dnp no)
		(property "Reference" "#PWR045"
			(at 38.735 255.905 0)
			(effects
				(font
					(size 1.27 1.27)
					(thickness 0.15)
				)
				(justify left bottom)
				(hide yes)
			)
		)
		(property "Value" "GND"
			(at 27.94 257.81 0)
			(effects
				(font
					(size 1.27 1.27)
				)
				(justify left bottom)
			)
		)
		(property "Footprint" ""
			(at 38.735 260.985 0)
			(effects
				(font
					(size 1.27 1.27)
					(thickness 0.15)
				)
				(justify left bottom)
				(hide yes)
			)
		)
		(property "Datasheet" ""
			(at 38.735 266.065 0)
			(effects
				(font
					(size 1.27 1.27)
					(thickness 0.15)
				)
				(justify left bottom)
				(hide yes)
			)
		)
		(property "Description" ""
			(at 29.845 253.365 0)
			(effects
				(font
					(size 1.27 1.27)
				)
			)
		)
		(property "Author" "Antmicro"
			(at 38.735 260.985 0)
			(effects
				(font
					(size 1.27 1.27)
					(thickness 0.15)
				)
				(justify left bottom)
				(hide yes)
			)
		)
		(property "License" "Apache-2.0"
			(at 38.735 263.525 0)
			(effects
				(font
					(size 1.27 1.27)
					(thickness 0.15)
				)
				(justify left bottom)
				(hide yes)
			)
		)
		(pin "1"
		)
		(instances
			(project "lpddr4-test-board"
				(path ""
					(reference "#PWR045")
					(unit 1)
				)
			)
		)
	)
	(symbol
		(lib_id "antmicroTVSDiodes:TPD6E05U06RVZR")
		(at 54.61 251.46 0)
		(unit 1)
		(exclude_from_sim no)
		(in_bom yes)
		(on_board yes)
		(dnp no)
		(property "Reference" "D7"
			(at 59.055 248.92 0)
			(effects
				(font
					(size 1.27 1.27)
					(thickness 0.15)
				)
				(justify left bottom)
			)
		)
		(property "Value" "TPD6E05U06RVZR"
			(at 66.04 270.51 90)
			(effects
				(font
					(size 1.27 1.27)
				)
				(justify left bottom)
			)
		)
		(property "Footprint" "antmicro-footprints:USON-14_3.5X1.3X0.5mm_P0.5mm"
			(at 77.47 256.54 0)
			(effects
				(font
					(size 1.27 1.27)
					(thickness 0.15)
				)
				(justify left bottom)
				(hide yes)
			)
		)
		(property "Datasheet" "http://www.ti.com/lit/ds/symlink/tpd6e05u06.pdf"
			(at 77.47 259.08 0)
			(effects
				(font
					(size 1.27 1.27)
					(thickness 0.15)
				)
				(justify left bottom)
				(hide yes)
			)
		)
		(property "Description" ""
			(at 54.61 251.46 0)
			(effects
				(font
					(size 1.27 1.27)
				)
			)
		)
		(property "MPN" "TPD6E05U06RVZR"
			(at 77.47 261.62 0)
			(effects
				(font
					(size 1.27 1.27)
					(thickness 0.15)
				)
				(justify left bottom)
				(hide yes)
			)
		)
		(property "Manufacturer" "Texas Instruments"
			(at 77.47 264.16 0)
			(effects
				(font
					(size 1.27 1.27)
					(thickness 0.15)
				)
				(justify left bottom)
				(hide yes)
			)
		)
		(property "Author" "Antmicro"
			(at 77.47 266.7 0)
			(effects
				(font
					(size 1.27 1.27)
					(thickness 0.15)
				)
				(justify left bottom)
				(hide yes)
			)
		)
		(property "License" "Apache-2.0"
			(at 77.47 269.24 0)
			(effects
				(font
					(size 1.27 1.27)
					(thickness 0.15)
				)
				(justify left bottom)
				(hide yes)
			)
		)
		(pin "1"
		)
		(pin "2"
		)
		(pin "3"
		)
		(pin "4"
		)
		(pin "6"
		)
		(pin "7"
		)
		(pin "10"
		)
		(pin "11"
		)
		(pin "12"
		)
		(pin "13"
		)
		(pin "14"
		)
		(pin "5"
		)
		(pin "8"
		)
		(pin "9"
		)
		(instances
			(project "lpddr4-test-board"
				(path ""
					(reference "D7")
					(unit 1)
				)
			)
		)
	)
	(symbol
		(lib_id "antmicropower:GND")
		(at 52.07 276.86 0)
		(unit 1)
		(exclude_from_sim no)
		(in_bom yes)
		(on_board yes)
		(dnp no)
		(property "Reference" "#PWR047"
			(at 60.96 279.4 0)
			(effects
				(font
					(size 1.27 1.27)
					(thickness 0.15)
				)
				(justify left bottom)
				(hide yes)
			)
		)
		(property "Value" "GND"
			(at 50.165 281.305 0)
			(effects
				(font
					(size 1.27 1.27)
				)
				(justify left bottom)
			)
		)
		(property "Footprint" ""
			(at 60.96 284.48 0)
			(effects
				(font
					(size 1.27 1.27)
					(thickness 0.15)
				)
				(justify left bottom)
				(hide yes)
			)
		)
		(property "Datasheet" ""
			(at 60.96 289.56 0)
			(effects
				(font
					(size 1.27 1.27)
					(thickness 0.15)
				)
				(justify left bottom)
				(hide yes)
			)
		)
		(property "Description" ""
			(at 52.07 276.86 0)
			(effects
				(font
					(size 1.27 1.27)
				)
			)
		)
		(property "Author" "Antmicro"
			(at 60.96 284.48 0)
			(effects
				(font
					(size 1.27 1.27)
					(thickness 0.15)
				)
				(justify left bottom)
				(hide yes)
			)
		)
		(property "License" "Apache-2.0"
			(at 60.96 287.02 0)
			(effects
				(font
					(size 1.27 1.27)
					(thickness 0.15)
				)
				(justify left bottom)
				(hide yes)
			)
		)
		(pin "1"
		)
		(instances
			(project "lpddr4-test-board"
				(path ""
					(reference "#PWR047")
					(unit 1)
				)
			)
		)
	)
	(symbol
		(lib_id "antmicroResistors0402:R_100R_0402")
		(at 92.71 121.285 270)
		(unit 1)
		(exclude_from_sim no)
		(in_bom no)
		(on_board yes)
		(dnp yes)
		(property "Reference" "R55"
			(at 93.98 123.825 90)
			(effects
				(font
					(size 1.27 1.27)
					(thickness 0.15)
				)
				(justify left bottom)
			)
		)
		(property "Value" "R_100R_0402"
			(at 88.9 121.285 0)
			(effects
				(font
					(size 1.27 1.27)
				)
				(justify left bottom)
				(hide yes)
			)
		)
		(property "Footprint" "antmicro-footprints:R_0402_1005Metric"
			(at 77.47 141.605 0)
			(effects
				(font
					(size 1.27 1.27)
					(thickness 0.15)
				)
				(justify left bottom)
				(hide yes)
			)
		)
		(property "Datasheet" "https://www.bourns.com/docs/product-datasheets/cr.pdf"
			(at 74.93 141.605 0)
			(effects
				(font
					(size 1.27 1.27)
					(thickness 0.15)
				)
				(justify left bottom)
				(hide yes)
			)
		)
		(property "Description" ""
			(at 92.71 121.285 0)
			(effects
				(font
					(size 1.27 1.27)
				)
			)
		)
		(property "Manufacturer" "Bourns"
			(at 69.85 141.605 0)
			(effects
				(font
					(size 1.27 1.27)
					(thickness 0.15)
				)
				(justify left bottom)
				(hide yes)
			)
		)
		(property "MPN" "CR0402-FX-1000GLF"
			(at 72.39 141.605 0)
			(effects
				(font
					(size 1.27 1.27)
					(thickness 0.15)
				)
				(justify left bottom)
				(hide yes)
			)
		)
		(property "Val" "100R"
			(at 93.98 125.7301 90)
			(effects
				(font
					(size 1.27 1.27)
					(thickness 0.15)
				)
				(justify left bottom)
			)
		)
		(property "License" "Apache-2.0"
			(at 67.31 141.605 0)
			(effects
				(font
					(size 1.27 1.27)
					(thickness 0.15)
				)
				(justify left bottom)
				(hide yes)
			)
		)
		(property "Author" "Antmicro"
			(at 64.77 141.605 0)
			(effects
				(font
					(size 1.27 1.27)
					(thickness 0.15)
				)
				(justify left bottom)
				(hide yes)
			)
		)
		(property "Tolerance" "1%"
			(at 82.55 141.605 0)
			(effects
				(font
					(size 1.27 1.27)
				)
				(justify left bottom)
				(hide yes)
			)
		)
		(pin "1"
		)
		(pin "2"
		)
		(instances
			(project "lpddr4-test-board"
				(path ""
					(reference "R55")
					(unit 1)
				)
			)
		)
	)
	(symbol
		(lib_id "antmicropower:GND")
		(at 48.26 122.555 0)
		(unit 1)
		(exclude_from_sim no)
		(in_bom yes)
		(on_board yes)
		(dnp no)
		(property "Reference" "#PWR048"
			(at 57.15 125.095 0)
			(effects
				(font
					(size 1.27 1.27)
					(thickness 0.15)
				)
				(justify left bottom)
				(hide yes)
			)
		)
		(property "Value" "GND"
			(at 46.355 127 0)
			(effects
				(font
					(size 1.27 1.27)
				)
				(justify left bottom)
			)
		)
		(property "Footprint" ""
			(at 57.15 130.175 0)
			(effects
				(font
					(size 1.27 1.27)
					(thickness 0.15)
				)
				(justify left bottom)
				(hide yes)
			)
		)
		(property "Datasheet" ""
			(at 57.15 135.255 0)
			(effects
				(font
					(size 1.27 1.27)
					(thickness 0.15)
				)
				(justify left bottom)
				(hide yes)
			)
		)
		(property "Description" ""
			(at 48.26 122.555 0)
			(effects
				(font
					(size 1.27 1.27)
				)
			)
		)
		(property "Author" "Antmicro"
			(at 57.15 130.175 0)
			(effects
				(font
					(size 1.27 1.27)
					(thickness 0.15)
				)
				(justify left bottom)
				(hide yes)
			)
		)
		(property "License" "Apache-2.0"
			(at 57.15 132.715 0)
			(effects
				(font
					(size 1.27 1.27)
					(thickness 0.15)
				)
				(justify left bottom)
				(hide yes)
			)
		)
		(pin "1"
		)
		(instances
			(project "lpddr4-test-board"
				(path ""
					(reference "#PWR048")
					(unit 1)
				)
			)
		)
	)
	(symbol
		(lib_id "antmicroGenericPinHeaders:PinHeader_1x3_P2.54mm_Drill1.1mm")
		(at 219.71 268.605 0)
		(mirror x)
		(unit 1)
		(exclude_from_sim no)
		(in_bom yes)
		(on_board yes)
		(dnp no)
		(property "Reference" "MODE1"
			(at 226.06 266.065 90)
			(effects
				(font
					(size 1.27 1.27)
					(thickness 0.15)
				)
			)
		)
		(property "Value" "PinHeader_1x3_P2.54mm_Drill1.1mm"
			(at 223.52 259.715 0)
			(effects
				(font
					(size 1.27 1.27)
				)
				(hide yes)
			)
		)
		(property "Footprint" "antmicro-footprints:PinHeader_1x3_P2.54mm_Drill1.1mm"
			(at 240.03 255.905 0)
			(effects
				(font
					(size 1.27 1.27)
					(thickness 0.15)
				)
				(justify left bottom)
				(hide yes)
			)
		)
		(property "Datasheet" "https://katalog.we-online.de/em/datasheet/6130xx11121.pdf"
			(at 240.03 253.365 0)
			(effects
				(font
					(size 1.27 1.27)
					(thickness 0.15)
				)
				(justify left bottom)
				(hide yes)
			)
		)
		(property "Description" ""
			(at 219.71 268.605 0)
			(effects
				(font
					(size 1.27 1.27)
				)
			)
		)
		(property "MPN" "61300311121"
			(at 222.25 270.51 0)
			(effects
				(font
					(size 1.27 1.27)
					(thickness 0.15)
				)
				(justify left bottom)
			)
		)
		(property "Manufacturer" "Würth Elektronik"
			(at 240.03 250.825 0)
			(effects
				(font
					(size 1.27 1.27)
					(thickness 0.15)
				)
				(justify left bottom)
				(hide yes)
			)
		)
		(property "Author" "Antmicro"
			(at 240.03 245.745 0)
			(effects
				(font
					(size 1.27 1.27)
					(thickness 0.15)
				)
				(justify left bottom)
				(hide yes)
			)
		)
		(property "License" "Apache-2.0"
			(at 240.03 243.205 0)
			(effects
				(font
					(size 1.27 1.27)
					(thickness 0.15)
				)
				(justify left bottom)
				(hide yes)
			)
		)
		(property "VSD_class" "IO Header"
			(at 240.03 248.285 0)
			(effects
				(font
					(size 1.27 1.27)
					(thickness 0.15)
				)
				(justify left bottom)
				(hide yes)
			)
		)
		(pin "1"
		)
		(pin "2"
		)
		(pin "3"
		)
		(instances
			(project "lpddr4-test-board"
				(path ""
					(reference "MODE1")
					(unit 1)
				)
			)
		)
	)
	(symbol
		(lib_id "antmicroPushbuttonSwitches:SW_B3U-1000P_SMD")
		(at 288.925 131.445 270)
		(unit 1)
		(exclude_from_sim no)
		(in_bom yes)
		(on_board yes)
		(dnp no)
		(property "Reference" "PROG_B1"
			(at 285.75 132.08 0)
			(effects
				(font
					(size 1.27 1.27)
					(thickness 0.15)
				)
				(justify left)
			)
		)
		(property "Value" "SW_B3U-1000P"
			(at 293.37 129.54 0)
			(effects
				(font
					(size 1.27 1.27)
				)
				(justify left)
			)
		)
		(property "Footprint" "antmicro-footprints:SW_B3U-1000P_SMD"
			(at 281.305 156.845 0)
			(effects
				(font
					(size 1.27 1.27)
					(thickness 0.15)
				)
				(justify left bottom)
				(hide yes)
			)
		)
		(property "Datasheet" "https://omronfs.omron.com/en_US/ecb/products/pdf/en-b3u.pdf"
			(at 278.765 156.845 0)
			(effects
				(font
					(size 1.27 1.27)
					(thickness 0.15)
				)
				(justify left bottom)
				(hide yes)
			)
		)
		(property "Description" ""
			(at 288.925 131.445 0)
			(effects
				(font
					(size 1.27 1.27)
				)
			)
		)
		(property "MPN" "B3U-1000P"
			(at 276.225 156.845 0)
			(effects
				(font
					(size 1.27 1.27)
					(thickness 0.15)
				)
				(justify left bottom)
			)
		)
		(property "Manufacturer" "Omron"
			(at 273.685 156.845 0)
			(effects
				(font
					(size 1.27 1.27)
					(thickness 0.15)
				)
				(justify left bottom)
				(hide yes)
			)
		)
		(property "Author" "Antmicro"
			(at 271.145 156.845 0)
			(effects
				(font
					(size 1.27 1.27)
					(thickness 0.15)
				)
				(justify left bottom)
				(hide yes)
			)
		)
		(property "License" "Apache-2.0"
			(at 268.605 156.845 0)
			(effects
				(font
					(size 1.27 1.27)
					(thickness 0.15)
				)
				(justify left bottom)
				(hide yes)
			)
		)
		(pin "1"
		)
		(pin "2"
		)
		(instances
			(project "lpddr4-test-board"
				(path ""
					(reference "PROG_B1")
					(unit 1)
				)
			)
		)
	)
	(symbol
		(lib_id "antmicroResistors0402:R_4k7_0402")
		(at 288.925 113.03 270)
		(unit 1)
		(exclude_from_sim no)
		(in_bom yes)
		(on_board yes)
		(dnp no)
		(property "Reference" "R67"
			(at 290.195 115.57 90)
			(effects
				(font
					(size 1.27 1.27)
					(thickness 0.15)
				)
				(justify left bottom)
			)
		)
		(property "Value" "R_4k7_0402"
			(at 285.115 113.03 0)
			(effects
				(font
					(size 1.27 1.27)
				)
				(justify left bottom)
				(hide yes)
			)
		)
		(property "Footprint" "antmicro-footprints:R_0402_1005Metric"
			(at 273.685 133.35 0)
			(effects
				(font
					(size 1.27 1.27)
					(thickness 0.15)
				)
				(justify left bottom)
				(hide yes)
			)
		)
		(property "Datasheet" "https://www.bourns.com/docs/product-datasheets/cr.pdf"
			(at 271.145 133.35 0)
			(effects
				(font
					(size 1.27 1.27)
					(thickness 0.15)
				)
				(justify left bottom)
				(hide yes)
			)
		)
		(property "Description" ""
			(at 288.925 113.03 0)
			(effects
				(font
					(size 1.27 1.27)
				)
			)
		)
		(property "Manufacturer" "Bourns"
			(at 266.065 133.35 0)
			(effects
				(font
					(size 1.27 1.27)
					(thickness 0.15)
				)
				(justify left bottom)
				(hide yes)
			)
		)
		(property "MPN" "CR0402-FX-4701GLF"
			(at 268.605 133.35 0)
			(effects
				(font
					(size 1.27 1.27)
					(thickness 0.15)
				)
				(justify left bottom)
				(hide yes)
			)
		)
		(property "Val" "4k7"
			(at 290.195 117.4751 90)
			(effects
				(font
					(size 1.27 1.27)
					(thickness 0.15)
				)
				(justify left bottom)
			)
		)
		(property "License" "Apache-2.0"
			(at 263.525 133.35 0)
			(effects
				(font
					(size 1.27 1.27)
					(thickness 0.15)
				)
				(justify left bottom)
				(hide yes)
			)
		)
		(property "Author" "Antmicro"
			(at 260.985 133.35 0)
			(effects
				(font
					(size 1.27 1.27)
					(thickness 0.15)
				)
				(justify left bottom)
				(hide yes)
			)
		)
		(property "Tolerance" "1%"
			(at 278.765 133.35 0)
			(effects
				(font
					(size 1.27 1.27)
				)
				(justify left bottom)
				(hide yes)
			)
		)
		(pin "1"
		)
		(pin "2"
		)
		(instances
			(project "lpddr4-test-board"
				(path ""
					(reference "R67")
					(unit 1)
				)
			)
		)
	)
	(symbol
		(lib_id "antmicroResistors0402:R_330R_0402")
		(at 297.815 113.03 270)
		(unit 1)
		(exclude_from_sim no)
		(in_bom yes)
		(on_board yes)
		(dnp no)
		(property "Reference" "R68"
			(at 299.085 115.57 90)
			(effects
				(font
					(size 1.27 1.27)
					(thickness 0.15)
				)
				(justify left bottom)
			)
		)
		(property "Value" "R_330R_0402"
			(at 294.005 113.03 0)
			(effects
				(font
					(size 1.27 1.27)
				)
				(justify left bottom)
				(hide yes)
			)
		)
		(property "Footprint" "antmicro-footprints:R_0402_1005Metric"
			(at 282.575 133.35 0)
			(effects
				(font
					(size 1.27 1.27)
					(thickness 0.15)
				)
				(justify left bottom)
				(hide yes)
			)
		)
		(property "Datasheet" "https://www.bourns.com/docs/product-datasheets/cr.pdf"
			(at 280.035 133.35 0)
			(effects
				(font
					(size 1.27 1.27)
					(thickness 0.15)
				)
				(justify left bottom)
				(hide yes)
			)
		)
		(property "Description" ""
			(at 297.815 113.03 0)
			(effects
				(font
					(size 1.27 1.27)
				)
			)
		)
		(property "Manufacturer" "Bourns"
			(at 274.955 133.35 0)
			(effects
				(font
					(size 1.27 1.27)
					(thickness 0.15)
				)
				(justify left bottom)
				(hide yes)
			)
		)
		(property "MPN" "CR0402-FX-3300GLF"
			(at 277.495 133.35 0)
			(effects
				(font
					(size 1.27 1.27)
					(thickness 0.15)
				)
				(justify left bottom)
				(hide yes)
			)
		)
		(property "Val" "330R"
			(at 299.085 117.4751 90)
			(effects
				(font
					(size 1.27 1.27)
					(thickness 0.15)
				)
				(justify left bottom)
			)
		)
		(property "License" "Apache-2.0"
			(at 272.415 133.35 0)
			(effects
				(font
					(size 1.27 1.27)
					(thickness 0.15)
				)
				(justify left bottom)
				(hide yes)
			)
		)
		(property "Author" "Antmicro"
			(at 269.875 133.35 0)
			(effects
				(font
					(size 1.27 1.27)
					(thickness 0.15)
				)
				(justify left bottom)
				(hide yes)
			)
		)
		(property "Tolerance" "1%"
			(at 287.655 133.35 0)
			(effects
				(font
					(size 1.27 1.27)
				)
				(justify left bottom)
				(hide yes)
			)
		)
		(pin "1"
		)
		(pin "2"
		)
		(instances
			(project "lpddr4-test-board"
				(path ""
					(reference "R68")
					(unit 1)
				)
			)
		)
	)
	(symbol
		(lib_id "antmicroResistors0402:R_330R_0402")
		(at 133.985 234.95 0)
		(unit 1)
		(exclude_from_sim no)
		(in_bom yes)
		(on_board yes)
		(dnp no)
		(property "Reference" "R57"
			(at 139.065 234.95 0)
			(effects
				(font
					(size 1.27 1.27)
					(thickness 0.15)
				)
				(justify left bottom)
			)
		)
		(property "Value" "R_330R_0402"
			(at 133.985 238.76 0)
			(effects
				(font
					(size 1.27 1.27)
				)
				(justify left bottom)
				(hide yes)
			)
		)
		(property "Footprint" "antmicro-footprints:R_0402_1005Metric"
			(at 154.305 250.19 0)
			(effects
				(font
					(size 1.27 1.27)
					(thickness 0.15)
				)
				(justify left bottom)
				(hide yes)
			)
		)
		(property "Datasheet" "https://www.bourns.com/docs/product-datasheets/cr.pdf"
			(at 154.305 252.73 0)
			(effects
				(font
					(size 1.27 1.27)
					(thickness 0.15)
				)
				(justify left bottom)
				(hide yes)
			)
		)
		(property "Description" ""
			(at 133.985 234.95 0)
			(effects
				(font
					(size 1.27 1.27)
				)
			)
		)
		(property "Manufacturer" "Bourns"
			(at 154.305 257.81 0)
			(effects
				(font
					(size 1.27 1.27)
					(thickness 0.15)
				)
				(justify left bottom)
				(hide yes)
			)
		)
		(property "MPN" "CR0402-FX-3300GLF"
			(at 154.305 255.27 0)
			(effects
				(font
					(size 1.27 1.27)
					(thickness 0.15)
				)
				(justify left bottom)
				(hide yes)
			)
		)
		(property "Val" "330R"
			(at 128.905 234.95 0)
			(effects
				(font
					(size 1.27 1.27)
					(thickness 0.15)
				)
				(justify left bottom)
			)
		)
		(property "License" "Apache-2.0"
			(at 154.305 260.35 0)
			(effects
				(font
					(size 1.27 1.27)
					(thickness 0.15)
				)
				(justify left bottom)
				(hide yes)
			)
		)
		(property "Author" "Antmicro"
			(at 154.305 262.89 0)
			(effects
				(font
					(size 1.27 1.27)
					(thickness 0.15)
				)
				(justify left bottom)
				(hide yes)
			)
		)
		(property "Tolerance" "1%"
			(at 154.305 245.11 0)
			(effects
				(font
					(size 1.27 1.27)
				)
				(justify left bottom)
				(hide yes)
			)
		)
		(pin "1"
		)
		(pin "2"
		)
		(instances
			(project "lpddr4-test-board"
				(path ""
					(reference "R57")
					(unit 1)
				)
			)
		)
	)
	(symbol
		(lib_id "antmicroLEDIndicationDiscrete:LED_G_0603_KP-1608CGCK")
		(at 118.745 234.95 0)
		(unit 1)
		(exclude_from_sim no)
		(in_bom yes)
		(on_board yes)
		(dnp no)
		(property "Reference" "D8"
			(at 120.65 229.87 0)
			(effects
				(font
					(size 1.27 1.27)
					(thickness 0.15)
				)
				(justify left bottom)
			)
		)
		(property "Value" "LED_G_0603_KP-1608CGCK"
			(at 108.585 232.41 0)
			(effects
				(font
					(size 1.27 1.27)
				)
				(justify left bottom)
			)
		)
		(property "Footprint" "antmicro-footprints:LED_0603_1608Metric_G"
			(at 141.605 245.11 0)
			(effects
				(font
					(size 1.27 1.27)
					(thickness 0.15)
				)
				(justify left bottom)
				(hide yes)
			)
		)
		(property "Datasheet" "http://www.farnell.com/datasheets/2045956.pdf"
			(at 141.605 247.65 0)
			(effects
				(font
					(size 1.27 1.27)
					(thickness 0.15)
				)
				(justify left bottom)
				(hide yes)
			)
		)
		(property "Description" ""
			(at 118.745 234.95 0)
			(effects
				(font
					(size 1.27 1.27)
				)
			)
		)
		(property "MPN" "KP-1608CGCK"
			(at 141.605 250.19 0)
			(effects
				(font
					(size 1.27 1.27)
					(thickness 0.15)
				)
				(justify left bottom)
				(hide yes)
			)
		)
		(property "Manufacturer" "Kingbright"
			(at 141.605 252.73 0)
			(effects
				(font
					(size 1.27 1.27)
					(thickness 0.15)
				)
				(justify left bottom)
				(hide yes)
			)
		)
		(property "Author" "Antmicro"
			(at 141.605 255.27 0)
			(effects
				(font
					(size 1.27 1.27)
					(thickness 0.15)
				)
				(justify left bottom)
				(hide yes)
			)
		)
		(property "License" "Apache-2.0"
			(at 141.605 257.81 0)
			(effects
				(font
					(size 1.27 1.27)
					(thickness 0.15)
				)
				(justify left bottom)
				(hide yes)
			)
		)
		(pin "1"
		)
		(pin "2"
		)
		(instances
			(project "lpddr4-test-board"
				(path ""
					(reference "D8")
					(unit 1)
				)
			)
		)
	)
	(symbol
		(lib_id "antmicroResistors0402:R_330R_0402")
		(at 134.62 254.635 0)
		(unit 1)
		(exclude_from_sim no)
		(in_bom yes)
		(on_board yes)
		(dnp no)
		(property "Reference" "R58"
			(at 139.7 254.635 0)
			(effects
				(font
					(size 1.27 1.27)
					(thickness 0.15)
				)
				(justify left bottom)
			)
		)
		(property "Value" "R_330R_0402"
			(at 134.62 258.445 0)
			(effects
				(font
					(size 1.27 1.27)
				)
				(justify left bottom)
				(hide yes)
			)
		)
		(property "Footprint" "antmicro-footprints:R_0402_1005Metric"
			(at 154.94 269.875 0)
			(effects
				(font
					(size 1.27 1.27)
					(thickness 0.15)
				)
				(justify left bottom)
				(hide yes)
			)
		)
		(property "Datasheet" "https://www.bourns.com/docs/product-datasheets/cr.pdf"
			(at 154.94 272.415 0)
			(effects
				(font
					(size 1.27 1.27)
					(thickness 0.15)
				)
				(justify left bottom)
				(hide yes)
			)
		)
		(property "Description" ""
			(at 134.62 254.635 0)
			(effects
				(font
					(size 1.27 1.27)
				)
			)
		)
		(property "Manufacturer" "Bourns"
			(at 154.94 277.495 0)
			(effects
				(font
					(size 1.27 1.27)
					(thickness 0.15)
				)
				(justify left bottom)
				(hide yes)
			)
		)
		(property "MPN" "CR0402-FX-3300GLF"
			(at 154.94 274.955 0)
			(effects
				(font
					(size 1.27 1.27)
					(thickness 0.15)
				)
				(justify left bottom)
				(hide yes)
			)
		)
		(property "Val" "330R"
			(at 129.54 254.635 0)
			(effects
				(font
					(size 1.27 1.27)
					(thickness 0.15)
				)
				(justify left bottom)
			)
		)
		(property "License" "Apache-2.0"
			(at 154.94 280.035 0)
			(effects
				(font
					(size 1.27 1.27)
					(thickness 0.15)
				)
				(justify left bottom)
				(hide yes)
			)
		)
		(property "Author" "Antmicro"
			(at 154.94 282.575 0)
			(effects
				(font
					(size 1.27 1.27)
					(thickness 0.15)
				)
				(justify left bottom)
				(hide yes)
			)
		)
		(property "Tolerance" "1%"
			(at 154.94 264.795 0)
			(effects
				(font
					(size 1.27 1.27)
				)
				(justify left bottom)
				(hide yes)
			)
		)
		(pin "1"
		)
		(pin "2"
		)
		(instances
			(project "lpddr4-test-board"
				(path ""
					(reference "R58")
					(unit 1)
				)
			)
		)
	)
	(symbol
		(lib_id "antmicroLEDIndicationDiscrete:LED_G_0603_KP-1608CGCK")
		(at 119.38 254.635 0)
		(unit 1)
		(exclude_from_sim no)
		(in_bom yes)
		(on_board yes)
		(dnp no)
		(property "Reference" "D9"
			(at 121.285 249.555 0)
			(effects
				(font
					(size 1.27 1.27)
					(thickness 0.15)
				)
				(justify left bottom)
			)
		)
		(property "Value" "LED_G_0603_KP-1608CGCK"
			(at 109.22 252.095 0)
			(effects
				(font
					(size 1.27 1.27)
				)
				(justify left bottom)
			)
		)
		(property "Footprint" "antmicro-footprints:LED_0603_1608Metric_G"
			(at 142.24 264.795 0)
			(effects
				(font
					(size 1.27 1.27)
					(thickness 0.15)
				)
				(justify left bottom)
				(hide yes)
			)
		)
		(property "Datasheet" "http://www.farnell.com/datasheets/2045956.pdf"
			(at 142.24 267.335 0)
			(effects
				(font
					(size 1.27 1.27)
					(thickness 0.15)
				)
				(justify left bottom)
				(hide yes)
			)
		)
		(property "Description" ""
			(at 119.38 254.635 0)
			(effects
				(font
					(size 1.27 1.27)
				)
			)
		)
		(property "MPN" "KP-1608CGCK"
			(at 142.24 269.875 0)
			(effects
				(font
					(size 1.27 1.27)
					(thickness 0.15)
				)
				(justify left bottom)
				(hide yes)
			)
		)
		(property "Manufacturer" "Kingbright"
			(at 142.24 272.415 0)
			(effects
				(font
					(size 1.27 1.27)
					(thickness 0.15)
				)
				(justify left bottom)
				(hide yes)
			)
		)
		(property "Author" "Antmicro"
			(at 142.24 274.955 0)
			(effects
				(font
					(size 1.27 1.27)
					(thickness 0.15)
				)
				(justify left bottom)
				(hide yes)
			)
		)
		(property "License" "Apache-2.0"
			(at 142.24 277.495 0)
			(effects
				(font
					(size 1.27 1.27)
					(thickness 0.15)
				)
				(justify left bottom)
				(hide yes)
			)
		)
		(pin "1"
		)
		(pin "2"
		)
		(instances
			(project "lpddr4-test-board"
				(path ""
					(reference "D9")
					(unit 1)
				)
			)
		)
	)
	(symbol
		(lib_id "antmicroTransistorsFETsMOSFETsSingle:BSS138PW")
		(at 153.035 242.57 90)
		(unit 1)
		(exclude_from_sim no)
		(in_bom yes)
		(on_board yes)
		(dnp no)
		(property "Reference" "Q6"
			(at 149.225 230.505 90)
			(effects
				(font
					(size 1.27 1.27)
					(thickness 0.15)
				)
				(justify right top)
			)
		)
		(property "Value" "BSS138PW"
			(at 145.415 232.41 90)
			(effects
				(font
					(size 1.27 1.27)
				)
				(justify right top)
			)
		)
		(property "Footprint" "antmicro-footprints:SC70-3"
			(at 164.465 219.71 0)
			(effects
				(font
					(size 1.27 1.27)
					(thickness 0.15)
				)
				(justify left bottom)
				(hide yes)
			)
		)
		(property "Datasheet" "https://assets.nexperia.com/documents/data-sheet/BSS138PW.pdf"
			(at 167.005 219.71 0)
			(effects
				(font
					(size 1.27 1.27)
					(thickness 0.15)
				)
				(justify left bottom)
				(hide yes)
			)
		)
		(property "Description" ""
			(at 153.035 242.57 0)
			(effects
				(font
					(size 1.27 1.27)
				)
			)
		)
		(property "MPN" "BSS138PW"
			(at 169.545 219.71 0)
			(effects
				(font
					(size 1.27 1.27)
					(thickness 0.15)
				)
				(justify left bottom)
				(hide yes)
			)
		)
		(property "Manufacturer" "Nexperia"
			(at 172.085 219.71 0)
			(effects
				(font
					(size 1.27 1.27)
					(thickness 0.15)
				)
				(justify left bottom)
				(hide yes)
			)
		)
		(property "Author" "Antmicro"
			(at 174.625 219.71 0)
			(effects
				(font
					(size 1.27 1.27)
					(thickness 0.15)
				)
				(justify left bottom)
				(hide yes)
			)
		)
		(property "License" "Apache-2.0"
			(at 177.165 219.71 0)
			(effects
				(font
					(size 1.27 1.27)
					(thickness 0.15)
				)
				(justify left bottom)
				(hide yes)
			)
		)
		(pin "1"
		)
		(pin "2"
		)
		(pin "3"
		)
		(instances
			(project "lpddr4-test-board"
				(path ""
					(reference "Q6")
					(unit 1)
				)
			)
		)
	)
	(symbol
		(lib_id "antmicroTransistorsFETsMOSFETsSingle:BSS138PW")
		(at 153.67 262.255 90)
		(unit 1)
		(exclude_from_sim no)
		(in_bom yes)
		(on_board yes)
		(dnp no)
		(property "Reference" "Q7"
			(at 149.86 250.19 90)
			(effects
				(font
					(size 1.27 1.27)
					(thickness 0.15)
				)
				(justify right top)
			)
		)
		(property "Value" "BSS138PW"
			(at 146.05 252.095 90)
			(effects
				(font
					(size 1.27 1.27)
				)
				(justify right top)
			)
		)
		(property "Footprint" "antmicro-footprints:SC70-3"
			(at 165.1 239.395 0)
			(effects
				(font
					(size 1.27 1.27)
					(thickness 0.15)
				)
				(justify left bottom)
				(hide yes)
			)
		)
		(property "Datasheet" "https://assets.nexperia.com/documents/data-sheet/BSS138PW.pdf"
			(at 167.64 239.395 0)
			(effects
				(font
					(size 1.27 1.27)
					(thickness 0.15)
				)
				(justify left bottom)
				(hide yes)
			)
		)
		(property "Description" ""
			(at 153.67 262.255 0)
			(effects
				(font
					(size 1.27 1.27)
				)
			)
		)
		(property "MPN" "BSS138PW"
			(at 170.18 239.395 0)
			(effects
				(font
					(size 1.27 1.27)
					(thickness 0.15)
				)
				(justify left bottom)
				(hide yes)
			)
		)
		(property "Manufacturer" "Nexperia"
			(at 172.72 239.395 0)
			(effects
				(font
					(size 1.27 1.27)
					(thickness 0.15)
				)
				(justify left bottom)
				(hide yes)
			)
		)
		(property "Author" "Antmicro"
			(at 175.26 239.395 0)
			(effects
				(font
					(size 1.27 1.27)
					(thickness 0.15)
				)
				(justify left bottom)
				(hide yes)
			)
		)
		(property "License" "Apache-2.0"
			(at 177.8 239.395 0)
			(effects
				(font
					(size 1.27 1.27)
					(thickness 0.15)
				)
				(justify left bottom)
				(hide yes)
			)
		)
		(pin "1"
		)
		(pin "2"
		)
		(pin "3"
		)
		(instances
			(project "lpddr4-test-board"
				(path ""
					(reference "Q7")
					(unit 1)
				)
			)
		)
	)
	(symbol
		(lib_id "antmicropower:GND")
		(at 288.925 144.145 0)
		(unit 1)
		(exclude_from_sim no)
		(in_bom yes)
		(on_board yes)
		(dnp no)
		(property "Reference" "#PWR056"
			(at 297.815 146.685 0)
			(effects
				(font
					(size 1.27 1.27)
					(thickness 0.15)
				)
				(justify left bottom)
				(hide yes)
			)
		)
		(property "Value" "GND"
			(at 287.02 148.59 0)
			(effects
				(font
					(size 1.27 1.27)
				)
				(justify left bottom)
			)
		)
		(property "Footprint" ""
			(at 297.815 151.765 0)
			(effects
				(font
					(size 1.27 1.27)
					(thickness 0.15)
				)
				(justify left bottom)
				(hide yes)
			)
		)
		(property "Datasheet" ""
			(at 297.815 156.845 0)
			(effects
				(font
					(size 1.27 1.27)
					(thickness 0.15)
				)
				(justify left bottom)
				(hide yes)
			)
		)
		(property "Description" ""
			(at 288.925 144.145 0)
			(effects
				(font
					(size 1.27 1.27)
				)
			)
		)
		(property "Author" "Antmicro"
			(at 297.815 151.765 0)
			(effects
				(font
					(size 1.27 1.27)
					(thickness 0.15)
				)
				(justify left bottom)
				(hide yes)
			)
		)
		(property "License" "Apache-2.0"
			(at 297.815 154.305 0)
			(effects
				(font
					(size 1.27 1.27)
					(thickness 0.15)
				)
				(justify left bottom)
				(hide yes)
			)
		)
		(pin "1"
		)
		(instances
			(project "lpddr4-test-board"
				(path ""
					(reference "#PWR056")
					(unit 1)
				)
			)
		)
	)
	(symbol
		(lib_id "antmicroResistors0402:R_0R_0402")
		(at 317.5 88.265 270)
		(unit 1)
		(exclude_from_sim no)
		(in_bom yes)
		(on_board yes)
		(dnp no)
		(property "Reference" "R69"
			(at 318.77 90.805 90)
			(effects
				(font
					(size 1.27 1.27)
					(thickness 0.15)
				)
				(justify left bottom)
			)
		)
		(property "Value" "R_0R_0402"
			(at 313.69 88.265 0)
			(effects
				(font
					(size 1.27 1.27)
				)
				(justify left bottom)
				(hide yes)
			)
		)
		(property "Footprint" "antmicro-footprints:R_0402_1005Metric"
			(at 302.26 108.585 0)
			(effects
				(font
					(size 1.27 1.27)
					(thickness 0.15)
				)
				(justify left bottom)
				(hide yes)
			)
		)
		(property "Datasheet" "https://industrial.panasonic.com/cdbs/www-data/pdf/RDA0000/AOA0000C301.pdf"
			(at 299.72 108.585 0)
			(effects
				(font
					(size 1.27 1.27)
					(thickness 0.15)
				)
				(justify left bottom)
				(hide yes)
			)
		)
		(property "Description" ""
			(at 317.5 88.265 0)
			(effects
				(font
					(size 1.27 1.27)
				)
			)
		)
		(property "Manufacturer" "Panasonic"
			(at 294.64 108.585 0)
			(effects
				(font
					(size 1.27 1.27)
					(thickness 0.15)
				)
				(justify left bottom)
				(hide yes)
			)
		)
		(property "MPN" "ERJ2GE0R00X"
			(at 297.18 108.585 0)
			(effects
				(font
					(size 1.27 1.27)
					(thickness 0.15)
				)
				(justify left bottom)
				(hide yes)
			)
		)
		(property "Val" "0R"
			(at 318.77 92.7099 90)
			(effects
				(font
					(size 1.27 1.27)
					(thickness 0.15)
				)
				(justify left bottom)
			)
		)
		(property "License" "Apache-2.0"
			(at 292.1 108.585 0)
			(effects
				(font
					(size 1.27 1.27)
					(thickness 0.15)
				)
				(justify left bottom)
				(hide yes)
			)
		)
		(property "Author" "Antmicro"
			(at 289.56 108.585 0)
			(effects
				(font
					(size 1.27 1.27)
					(thickness 0.15)
				)
				(justify left bottom)
				(hide yes)
			)
		)
		(property "Tolerance" "~"
			(at 307.34 108.585 0)
			(effects
				(font
					(size 1.27 1.27)
				)
				(justify left bottom)
				(hide yes)
			)
		)
		(property "Current" "1A"
			(at 287.02 108.585 0)
			(effects
				(font
					(size 1.27 1.27)
					(thickness 0.15)
				)
				(justify left bottom)
				(hide yes)
			)
		)
		(pin "1"
		)
		(pin "2"
		)
		(instances
			(project "lpddr4-test-board"
				(path ""
					(reference "R69")
					(unit 1)
				)
			)
		)
	)
	(symbol
		(lib_id "antmicroResistors0402:R_100R_0402")
		(at 172.085 105.41 270)
		(unit 1)
		(exclude_from_sim no)
		(in_bom yes)
		(on_board yes)
		(dnp no)
		(property "Reference" "R60"
			(at 173.355 107.9501 90)
			(effects
				(font
					(size 1.27 1.27)
					(thickness 0.15)
				)
				(justify left bottom)
			)
		)
		(property "Value" "R_100R_0402"
			(at 168.275 105.41 0)
			(effects
				(font
					(size 1.27 1.27)
				)
				(justify left bottom)
				(hide yes)
			)
		)
		(property "Footprint" "antmicro-footprints:R_0402_1005Metric"
			(at 156.845 125.73 0)
			(effects
				(font
					(size 1.27 1.27)
					(thickness 0.15)
				)
				(justify left bottom)
				(hide yes)
			)
		)
		(property "Datasheet" "https://www.bourns.com/docs/product-datasheets/cr.pdf"
			(at 154.305 125.73 0)
			(effects
				(font
					(size 1.27 1.27)
					(thickness 0.15)
				)
				(justify left bottom)
				(hide yes)
			)
		)
		(property "Description" ""
			(at 172.085 105.41 0)
			(effects
				(font
					(size 1.27 1.27)
				)
			)
		)
		(property "Manufacturer" "Bourns"
			(at 149.225 125.73 0)
			(effects
				(font
					(size 1.27 1.27)
					(thickness 0.15)
				)
				(justify left bottom)
				(hide yes)
			)
		)
		(property "MPN" "CR0402-FX-1000GLF"
			(at 151.765 125.73 0)
			(effects
				(font
					(size 1.27 1.27)
					(thickness 0.15)
				)
				(justify left bottom)
				(hide yes)
			)
		)
		(property "Val" "100R"
			(at 173.355 109.855 90)
			(effects
				(font
					(size 1.27 1.27)
					(thickness 0.15)
				)
				(justify left bottom)
			)
		)
		(property "License" "Apache-2.0"
			(at 146.685 125.73 0)
			(effects
				(font
					(size 1.27 1.27)
					(thickness 0.15)
				)
				(justify left bottom)
				(hide yes)
			)
		)
		(property "Author" "Antmicro"
			(at 144.145 125.73 0)
			(effects
				(font
					(size 1.27 1.27)
					(thickness 0.15)
				)
				(justify left bottom)
				(hide yes)
			)
		)
		(property "Tolerance" "1%"
			(at 161.925 125.73 0)
			(effects
				(font
					(size 1.27 1.27)
				)
				(justify left bottom)
				(hide yes)
			)
		)
		(pin "1"
		)
		(pin "2"
		)
		(instances
			(project "lpddr4-test-board"
				(path ""
					(reference "R60")
					(unit 1)
				)
			)
		)
	)
	(symbol
		(lib_id "antmicroResistors0402:R_100R_0402")
		(at 172.085 115.57 270)
		(unit 1)
		(exclude_from_sim no)
		(in_bom no)
		(on_board yes)
		(dnp yes)
		(property "Reference" "R61"
			(at 173.355 118.1101 90)
			(effects
				(font
					(size 1.27 1.27)
					(thickness 0.15)
				)
				(justify left bottom)
			)
		)
		(property "Value" "R_100R_0402"
			(at 168.275 115.57 0)
			(effects
				(font
					(size 1.27 1.27)
				)
				(justify left bottom)
				(hide yes)
			)
		)
		(property "Footprint" "antmicro-footprints:R_0402_1005Metric"
			(at 156.845 135.89 0)
			(effects
				(font
					(size 1.27 1.27)
					(thickness 0.15)
				)
				(justify left bottom)
				(hide yes)
			)
		)
		(property "Datasheet" "https://www.bourns.com/docs/product-datasheets/cr.pdf"
			(at 154.305 135.89 0)
			(effects
				(font
					(size 1.27 1.27)
					(thickness 0.15)
				)
				(justify left bottom)
				(hide yes)
			)
		)
		(property "Description" ""
			(at 172.085 115.57 0)
			(effects
				(font
					(size 1.27 1.27)
				)
			)
		)
		(property "Manufacturer" "Bourns"
			(at 149.225 135.89 0)
			(effects
				(font
					(size 1.27 1.27)
					(thickness 0.15)
				)
				(justify left bottom)
				(hide yes)
			)
		)
		(property "MPN" "CR0402-FX-1000GLF"
			(at 151.765 135.89 0)
			(effects
				(font
					(size 1.27 1.27)
					(thickness 0.15)
				)
				(justify left bottom)
				(hide yes)
			)
		)
		(property "Val" "100R"
			(at 173.355 120.015 90)
			(effects
				(font
					(size 1.27 1.27)
					(thickness 0.15)
				)
				(justify left bottom)
			)
		)
		(property "License" "Apache-2.0"
			(at 146.685 135.89 0)
			(effects
				(font
					(size 1.27 1.27)
					(thickness 0.15)
				)
				(justify left bottom)
				(hide yes)
			)
		)
		(property "Author" "Antmicro"
			(at 144.145 135.89 0)
			(effects
				(font
					(size 1.27 1.27)
					(thickness 0.15)
				)
				(justify left bottom)
				(hide yes)
			)
		)
		(property "Tolerance" "1%"
			(at 161.925 135.89 0)
			(effects
				(font
					(size 1.27 1.27)
				)
				(justify left bottom)
				(hide yes)
			)
		)
		(pin "1"
		)
		(pin "2"
		)
		(instances
			(project "lpddr4-test-board"
				(path ""
					(reference "R61")
					(unit 1)
				)
			)
		)
	)
	(symbol
		(lib_id "antmicropower:GND")
		(at 172.085 123.19 0)
		(unit 1)
		(exclude_from_sim no)
		(in_bom yes)
		(on_board yes)
		(dnp no)
		(property "Reference" "#PWR050"
			(at 180.975 125.73 0)
			(effects
				(font
					(size 1.27 1.27)
					(thickness 0.15)
				)
				(justify left bottom)
				(hide yes)
			)
		)
		(property "Value" "GND"
			(at 170.18 127.635 0)
			(effects
				(font
					(size 1.27 1.27)
				)
				(justify left bottom)
			)
		)
		(property "Footprint" ""
			(at 180.975 130.81 0)
			(effects
				(font
					(size 1.27 1.27)
					(thickness 0.15)
				)
				(justify left bottom)
				(hide yes)
			)
		)
		(property "Datasheet" ""
			(at 180.975 135.89 0)
			(effects
				(font
					(size 1.27 1.27)
					(thickness 0.15)
				)
				(justify left bottom)
				(hide yes)
			)
		)
		(property "Description" ""
			(at 172.085 123.19 0)
			(effects
				(font
					(size 1.27 1.27)
				)
			)
		)
		(property "Author" "Antmicro"
			(at 180.975 130.81 0)
			(effects
				(font
					(size 1.27 1.27)
					(thickness 0.15)
				)
				(justify left bottom)
				(hide yes)
			)
		)
		(property "License" "Apache-2.0"
			(at 180.975 133.35 0)
			(effects
				(font
					(size 1.27 1.27)
					(thickness 0.15)
				)
				(justify left bottom)
				(hide yes)
			)
		)
		(pin "1"
		)
		(instances
			(project "lpddr4-test-board"
				(path ""
					(reference "#PWR050")
					(unit 1)
				)
			)
		)
	)
	(symbol
		(lib_id "antmicroResistors0402:R_0R_0402")
		(at 74.93 109.855 0)
		(unit 1)
		(exclude_from_sim no)
		(in_bom yes)
		(on_board yes)
		(dnp no)
		(property "Reference" "R49"
			(at 80.01 109.855 0)
			(effects
				(font
					(size 1.27 1.27)
					(thickness 0.15)
				)
				(justify left bottom)
			)
		)
		(property "Value" "R_0R_0402"
			(at 74.93 113.665 0)
			(effects
				(font
					(size 1.27 1.27)
				)
				(justify left bottom)
				(hide yes)
			)
		)
		(property "Footprint" "antmicro-footprints:R_0402_1005Metric"
			(at 95.25 125.095 0)
			(effects
				(font
					(size 1.27 1.27)
					(thickness 0.15)
				)
				(justify left bottom)
				(hide yes)
			)
		)
		(property "Datasheet" "https://industrial.panasonic.com/cdbs/www-data/pdf/RDA0000/AOA0000C301.pdf"
			(at 95.25 127.635 0)
			(effects
				(font
					(size 1.27 1.27)
					(thickness 0.15)
				)
				(justify left bottom)
				(hide yes)
			)
		)
		(property "Description" ""
			(at 74.93 109.855 0)
			(effects
				(font
					(size 1.27 1.27)
				)
			)
		)
		(property "Manufacturer" "Panasonic"
			(at 95.25 132.715 0)
			(effects
				(font
					(size 1.27 1.27)
					(thickness 0.15)
				)
				(justify left bottom)
				(hide yes)
			)
		)
		(property "MPN" "ERJ2GE0R00X"
			(at 95.25 130.175 0)
			(effects
				(font
					(size 1.27 1.27)
					(thickness 0.15)
				)
				(justify left bottom)
				(hide yes)
			)
		)
		(property "Val" "0R"
			(at 71.755 109.855 0)
			(effects
				(font
					(size 1.27 1.27)
					(thickness 0.15)
				)
				(justify left bottom)
			)
		)
		(property "License" "Apache-2.0"
			(at 95.25 135.255 0)
			(effects
				(font
					(size 1.27 1.27)
					(thickness 0.15)
				)
				(justify left bottom)
				(hide yes)
			)
		)
		(property "Author" "Antmicro"
			(at 95.25 137.795 0)
			(effects
				(font
					(size 1.27 1.27)
					(thickness 0.15)
				)
				(justify left bottom)
				(hide yes)
			)
		)
		(property "Tolerance" "~"
			(at 95.25 120.015 0)
			(effects
				(font
					(size 1.27 1.27)
				)
				(justify left bottom)
				(hide yes)
			)
		)
		(property "Current" "1A"
			(at 95.25 140.335 0)
			(effects
				(font
					(size 1.27 1.27)
					(thickness 0.15)
				)
				(justify left bottom)
				(hide yes)
			)
		)
		(pin "1"
		)
		(pin "2"
		)
		(instances
			(project "lpddr4-test-board"
				(path ""
					(reference "R49")
					(unit 1)
				)
			)
		)
	)
	(symbol
		(lib_id "antmicroResistors0402:R_0R_0402")
		(at 74.93 112.395 0)
		(unit 1)
		(exclude_from_sim no)
		(in_bom yes)
		(on_board yes)
		(dnp no)
		(property "Reference" "R50"
			(at 80.01 112.395 0)
			(effects
				(font
					(size 1.27 1.27)
					(thickness 0.15)
				)
				(justify left bottom)
			)
		)
		(property "Value" "R_0R_0402"
			(at 74.93 116.205 0)
			(effects
				(font
					(size 1.27 1.27)
				)
				(justify left bottom)
				(hide yes)
			)
		)
		(property "Footprint" "antmicro-footprints:R_0402_1005Metric"
			(at 95.25 127.635 0)
			(effects
				(font
					(size 1.27 1.27)
					(thickness 0.15)
				)
				(justify left bottom)
				(hide yes)
			)
		)
		(property "Datasheet" "https://industrial.panasonic.com/cdbs/www-data/pdf/RDA0000/AOA0000C301.pdf"
			(at 95.25 130.175 0)
			(effects
				(font
					(size 1.27 1.27)
					(thickness 0.15)
				)
				(justify left bottom)
				(hide yes)
			)
		)
		(property "Description" ""
			(at 74.93 112.395 0)
			(effects
				(font
					(size 1.27 1.27)
				)
			)
		)
		(property "Manufacturer" "Panasonic"
			(at 95.25 135.255 0)
			(effects
				(font
					(size 1.27 1.27)
					(thickness 0.15)
				)
				(justify left bottom)
				(hide yes)
			)
		)
		(property "MPN" "ERJ2GE0R00X"
			(at 95.25 132.715 0)
			(effects
				(font
					(size 1.27 1.27)
					(thickness 0.15)
				)
				(justify left bottom)
				(hide yes)
			)
		)
		(property "Val" "0R"
			(at 71.755 112.395 0)
			(effects
				(font
					(size 1.27 1.27)
					(thickness 0.15)
				)
				(justify left bottom)
			)
		)
		(property "License" "Apache-2.0"
			(at 95.25 137.795 0)
			(effects
				(font
					(size 1.27 1.27)
					(thickness 0.15)
				)
				(justify left bottom)
				(hide yes)
			)
		)
		(property "Author" "Antmicro"
			(at 95.25 140.335 0)
			(effects
				(font
					(size 1.27 1.27)
					(thickness 0.15)
				)
				(justify left bottom)
				(hide yes)
			)
		)
		(property "Tolerance" "~"
			(at 95.25 122.555 0)
			(effects
				(font
					(size 1.27 1.27)
				)
				(justify left bottom)
				(hide yes)
			)
		)
		(property "Current" "1A"
			(at 95.25 142.875 0)
			(effects
				(font
					(size 1.27 1.27)
					(thickness 0.15)
				)
				(justify left bottom)
				(hide yes)
			)
		)
		(pin "1"
		)
		(pin "2"
		)
		(instances
			(project "lpddr4-test-board"
				(path ""
					(reference "R50")
					(unit 1)
				)
			)
		)
	)
	(symbol
		(lib_id "antmicroResistors0402:R_0R_0402")
		(at 74.93 117.475 0)
		(unit 1)
		(exclude_from_sim no)
		(in_bom yes)
		(on_board yes)
		(dnp no)
		(property "Reference" "R51"
			(at 80.01 117.475 0)
			(effects
				(font
					(size 1.27 1.27)
					(thickness 0.15)
				)
				(justify left bottom)
			)
		)
		(property "Value" "R_0R_0402"
			(at 74.93 121.285 0)
			(effects
				(font
					(size 1.27 1.27)
				)
				(justify left bottom)
				(hide yes)
			)
		)
		(property "Footprint" "antmicro-footprints:R_0402_1005Metric"
			(at 95.25 132.715 0)
			(effects
				(font
					(size 1.27 1.27)
					(thickness 0.15)
				)
				(justify left bottom)
				(hide yes)
			)
		)
		(property "Datasheet" "https://industrial.panasonic.com/cdbs/www-data/pdf/RDA0000/AOA0000C301.pdf"
			(at 95.25 135.255 0)
			(effects
				(font
					(size 1.27 1.27)
					(thickness 0.15)
				)
				(justify left bottom)
				(hide yes)
			)
		)
		(property "Description" ""
			(at 74.93 117.475 0)
			(effects
				(font
					(size 1.27 1.27)
				)
			)
		)
		(property "Manufacturer" "Panasonic"
			(at 95.25 140.335 0)
			(effects
				(font
					(size 1.27 1.27)
					(thickness 0.15)
				)
				(justify left bottom)
				(hide yes)
			)
		)
		(property "MPN" "ERJ2GE0R00X"
			(at 95.25 137.795 0)
			(effects
				(font
					(size 1.27 1.27)
					(thickness 0.15)
				)
				(justify left bottom)
				(hide yes)
			)
		)
		(property "Val" "0R"
			(at 71.755 117.475 0)
			(effects
				(font
					(size 1.27 1.27)
					(thickness 0.15)
				)
				(justify left bottom)
			)
		)
		(property "License" "Apache-2.0"
			(at 95.25 142.875 0)
			(effects
				(font
					(size 1.27 1.27)
					(thickness 0.15)
				)
				(justify left bottom)
				(hide yes)
			)
		)
		(property "Author" "Antmicro"
			(at 95.25 145.415 0)
			(effects
				(font
					(size 1.27 1.27)
					(thickness 0.15)
				)
				(justify left bottom)
				(hide yes)
			)
		)
		(property "Tolerance" "~"
			(at 95.25 127.635 0)
			(effects
				(font
					(size 1.27 1.27)
				)
				(justify left bottom)
				(hide yes)
			)
		)
		(property "Current" "1A"
			(at 95.25 147.955 0)
			(effects
				(font
					(size 1.27 1.27)
					(thickness 0.15)
				)
				(justify left bottom)
				(hide yes)
			)
		)
		(pin "1"
		)
		(pin "2"
		)
		(instances
			(project "lpddr4-test-board"
				(path ""
					(reference "R51")
					(unit 1)
				)
			)
		)
	)
	(symbol
		(lib_id "antmicroResistors0402:R_0R_0402")
		(at 74.93 120.015 0)
		(unit 1)
		(exclude_from_sim no)
		(in_bom yes)
		(on_board yes)
		(dnp no)
		(property "Reference" "R52"
			(at 80.01 120.015 0)
			(effects
				(font
					(size 1.27 1.27)
					(thickness 0.15)
				)
				(justify left bottom)
			)
		)
		(property "Value" "R_0R_0402"
			(at 74.93 123.825 0)
			(effects
				(font
					(size 1.27 1.27)
				)
				(justify left bottom)
				(hide yes)
			)
		)
		(property "Footprint" "antmicro-footprints:R_0402_1005Metric"
			(at 95.25 135.255 0)
			(effects
				(font
					(size 1.27 1.27)
					(thickness 0.15)
				)
				(justify left bottom)
				(hide yes)
			)
		)
		(property "Datasheet" "https://industrial.panasonic.com/cdbs/www-data/pdf/RDA0000/AOA0000C301.pdf"
			(at 95.25 137.795 0)
			(effects
				(font
					(size 1.27 1.27)
					(thickness 0.15)
				)
				(justify left bottom)
				(hide yes)
			)
		)
		(property "Description" ""
			(at 74.93 120.015 0)
			(effects
				(font
					(size 1.27 1.27)
				)
			)
		)
		(property "Manufacturer" "Panasonic"
			(at 95.25 142.875 0)
			(effects
				(font
					(size 1.27 1.27)
					(thickness 0.15)
				)
				(justify left bottom)
				(hide yes)
			)
		)
		(property "MPN" "ERJ2GE0R00X"
			(at 95.25 140.335 0)
			(effects
				(font
					(size 1.27 1.27)
					(thickness 0.15)
				)
				(justify left bottom)
				(hide yes)
			)
		)
		(property "Val" "0R"
			(at 71.755 120.015 0)
			(effects
				(font
					(size 1.27 1.27)
					(thickness 0.15)
				)
				(justify left bottom)
			)
		)
		(property "License" "Apache-2.0"
			(at 95.25 145.415 0)
			(effects
				(font
					(size 1.27 1.27)
					(thickness 0.15)
				)
				(justify left bottom)
				(hide yes)
			)
		)
		(property "Author" "Antmicro"
			(at 95.25 147.955 0)
			(effects
				(font
					(size 1.27 1.27)
					(thickness 0.15)
				)
				(justify left bottom)
				(hide yes)
			)
		)
		(property "Tolerance" "~"
			(at 95.25 130.175 0)
			(effects
				(font
					(size 1.27 1.27)
				)
				(justify left bottom)
				(hide yes)
			)
		)
		(property "Current" "1A"
			(at 95.25 150.495 0)
			(effects
				(font
					(size 1.27 1.27)
					(thickness 0.15)
				)
				(justify left bottom)
				(hide yes)
			)
		)
		(pin "1"
		)
		(pin "2"
		)
		(instances
			(project "lpddr4-test-board"
				(path ""
					(reference "R52")
					(unit 1)
				)
			)
		)
	)
	(symbol
		(lib_id "antmicroResistors0402:R_0R_0402")
		(at 74.93 104.775 0)
		(unit 1)
		(exclude_from_sim no)
		(in_bom yes)
		(on_board yes)
		(dnp no)
		(property "Reference" "R48"
			(at 80.01 104.775 0)
			(effects
				(font
					(size 1.27 1.27)
					(thickness 0.15)
				)
				(justify left bottom)
			)
		)
		(property "Value" "R_0R_0402"
			(at 74.93 108.585 0)
			(effects
				(font
					(size 1.27 1.27)
				)
				(justify left bottom)
				(hide yes)
			)
		)
		(property "Footprint" "antmicro-footprints:R_0402_1005Metric"
			(at 95.25 120.015 0)
			(effects
				(font
					(size 1.27 1.27)
					(thickness 0.15)
				)
				(justify left bottom)
				(hide yes)
			)
		)
		(property "Datasheet" "https://industrial.panasonic.com/cdbs/www-data/pdf/RDA0000/AOA0000C301.pdf"
			(at 95.25 122.555 0)
			(effects
				(font
					(size 1.27 1.27)
					(thickness 0.15)
				)
				(justify left bottom)
				(hide yes)
			)
		)
		(property "Description" ""
			(at 74.93 104.775 0)
			(effects
				(font
					(size 1.27 1.27)
				)
			)
		)
		(property "Manufacturer" "Panasonic"
			(at 95.25 127.635 0)
			(effects
				(font
					(size 1.27 1.27)
					(thickness 0.15)
				)
				(justify left bottom)
				(hide yes)
			)
		)
		(property "MPN" "ERJ2GE0R00X"
			(at 95.25 125.095 0)
			(effects
				(font
					(size 1.27 1.27)
					(thickness 0.15)
				)
				(justify left bottom)
				(hide yes)
			)
		)
		(property "Val" "0R"
			(at 71.755 104.775 0)
			(effects
				(font
					(size 1.27 1.27)
					(thickness 0.15)
				)
				(justify left bottom)
			)
		)
		(property "License" "Apache-2.0"
			(at 95.25 130.175 0)
			(effects
				(font
					(size 1.27 1.27)
					(thickness 0.15)
				)
				(justify left bottom)
				(hide yes)
			)
		)
		(property "Author" "Antmicro"
			(at 95.25 132.715 0)
			(effects
				(font
					(size 1.27 1.27)
					(thickness 0.15)
				)
				(justify left bottom)
				(hide yes)
			)
		)
		(property "Tolerance" "~"
			(at 95.25 114.935 0)
			(effects
				(font
					(size 1.27 1.27)
				)
				(justify left bottom)
				(hide yes)
			)
		)
		(property "Current" "1A"
			(at 95.25 135.255 0)
			(effects
				(font
					(size 1.27 1.27)
					(thickness 0.15)
				)
				(justify left bottom)
				(hide yes)
			)
		)
		(pin "1"
		)
		(pin "2"
		)
		(instances
			(project "lpddr4-test-board"
				(path ""
					(reference "R48")
					(unit 1)
				)
			)
		)
	)
	(symbol
		(lib_id "antmicroResistors0402:R_0R_0402")
		(at 74.93 102.235 0)
		(unit 1)
		(exclude_from_sim no)
		(in_bom yes)
		(on_board yes)
		(dnp no)
		(property "Reference" "R47"
			(at 80.01 102.235 0)
			(effects
				(font
					(size 1.27 1.27)
					(thickness 0.15)
				)
				(justify left bottom)
			)
		)
		(property "Value" "R_0R_0402"
			(at 74.93 106.045 0)
			(effects
				(font
					(size 1.27 1.27)
				)
				(justify left bottom)
				(hide yes)
			)
		)
		(property "Footprint" "antmicro-footprints:R_0402_1005Metric"
			(at 95.25 117.475 0)
			(effects
				(font
					(size 1.27 1.27)
					(thickness 0.15)
				)
				(justify left bottom)
				(hide yes)
			)
		)
		(property "Datasheet" "https://industrial.panasonic.com/cdbs/www-data/pdf/RDA0000/AOA0000C301.pdf"
			(at 95.25 120.015 0)
			(effects
				(font
					(size 1.27 1.27)
					(thickness 0.15)
				)
				(justify left bottom)
				(hide yes)
			)
		)
		(property "Description" ""
			(at 74.93 102.235 0)
			(effects
				(font
					(size 1.27 1.27)
				)
			)
		)
		(property "Manufacturer" "Panasonic"
			(at 95.25 125.095 0)
			(effects
				(font
					(size 1.27 1.27)
					(thickness 0.15)
				)
				(justify left bottom)
				(hide yes)
			)
		)
		(property "MPN" "ERJ2GE0R00X"
			(at 95.25 122.555 0)
			(effects
				(font
					(size 1.27 1.27)
					(thickness 0.15)
				)
				(justify left bottom)
				(hide yes)
			)
		)
		(property "Val" "0R"
			(at 71.755 102.235 0)
			(effects
				(font
					(size 1.27 1.27)
					(thickness 0.15)
				)
				(justify left bottom)
			)
		)
		(property "License" "Apache-2.0"
			(at 95.25 127.635 0)
			(effects
				(font
					(size 1.27 1.27)
					(thickness 0.15)
				)
				(justify left bottom)
				(hide yes)
			)
		)
		(property "Author" "Antmicro"
			(at 95.25 130.175 0)
			(effects
				(font
					(size 1.27 1.27)
					(thickness 0.15)
				)
				(justify left bottom)
				(hide yes)
			)
		)
		(property "Tolerance" "~"
			(at 95.25 112.395 0)
			(effects
				(font
					(size 1.27 1.27)
				)
				(justify left bottom)
				(hide yes)
			)
		)
		(property "Current" "1A"
			(at 95.25 132.715 0)
			(effects
				(font
					(size 1.27 1.27)
					(thickness 0.15)
				)
				(justify left bottom)
				(hide yes)
			)
		)
		(pin "1"
		)
		(pin "2"
		)
		(instances
			(project "lpddr4-test-board"
				(path ""
					(reference "R47")
					(unit 1)
				)
			)
		)
	)
	(symbol
		(lib_id "antmicroResistors0402:R_4k7_0402")
		(at 99.695 89.535 90)
		(mirror x)
		(unit 1)
		(exclude_from_sim no)
		(in_bom yes)
		(on_board yes)
		(dnp no)
		(property "Reference" "R56"
			(at 100.965 92.075 90)
			(effects
				(font
					(size 1.27 1.27)
					(thickness 0.15)
				)
				(justify right bottom)
			)
		)
		(property "Value" "R_4k7_0402"
			(at 103.505 89.535 0)
			(effects
				(font
					(size 1.27 1.27)
				)
				(justify left bottom)
				(hide yes)
			)
		)
		(property "Footprint" "antmicro-footprints:R_0402_1005Metric"
			(at 114.935 109.855 0)
			(effects
				(font
					(size 1.27 1.27)
					(thickness 0.15)
				)
				(justify left bottom)
				(hide yes)
			)
		)
		(property "Datasheet" "https://www.bourns.com/docs/product-datasheets/cr.pdf"
			(at 117.475 109.855 0)
			(effects
				(font
					(size 1.27 1.27)
					(thickness 0.15)
				)
				(justify left bottom)
				(hide yes)
			)
		)
		(property "Description" ""
			(at 99.695 89.535 0)
			(effects
				(font
					(size 1.27 1.27)
				)
			)
		)
		(property "Manufacturer" "Bourns"
			(at 122.555 109.855 0)
			(effects
				(font
					(size 1.27 1.27)
					(thickness 0.15)
				)
				(justify left bottom)
				(hide yes)
			)
		)
		(property "MPN" "CR0402-FX-4701GLF"
			(at 120.015 109.855 0)
			(effects
				(font
					(size 1.27 1.27)
					(thickness 0.15)
				)
				(justify left bottom)
				(hide yes)
			)
		)
		(property "Val" "4k7"
			(at 100.965 93.98 90)
			(effects
				(font
					(size 1.27 1.27)
					(thickness 0.15)
				)
				(justify right bottom)
			)
		)
		(property "License" "Apache-2.0"
			(at 125.095 109.855 0)
			(effects
				(font
					(size 1.27 1.27)
					(thickness 0.15)
				)
				(justify left bottom)
				(hide yes)
			)
		)
		(property "Author" "Antmicro"
			(at 127.635 109.855 0)
			(effects
				(font
					(size 1.27 1.27)
					(thickness 0.15)
				)
				(justify left bottom)
				(hide yes)
			)
		)
		(property "Tolerance" "1%"
			(at 109.855 109.855 0)
			(effects
				(font
					(size 1.27 1.27)
				)
				(justify left bottom)
				(hide yes)
			)
		)
		(pin "1"
		)
		(pin "2"
		)
		(instances
			(project "lpddr4-test-board"
				(path ""
					(reference "R56")
					(unit 1)
				)
			)
		)
	)
	(symbol
		(lib_id "antmicroResistors0402:R_4k7_0402")
		(at 106.68 94.615 90)
		(mirror x)
		(unit 1)
		(exclude_from_sim no)
		(in_bom yes)
		(on_board yes)
		(dnp no)
		(property "Reference" "R59"
			(at 111.76 97.155 90)
			(effects
				(font
					(size 1.27 1.27)
					(thickness 0.15)
				)
				(justify left bottom)
			)
		)
		(property "Value" "R_4k7_0402"
			(at 110.49 94.615 0)
			(effects
				(font
					(size 1.27 1.27)
				)
				(justify left bottom)
				(hide yes)
			)
		)
		(property "Footprint" "antmicro-footprints:R_0402_1005Metric"
			(at 121.92 114.935 0)
			(effects
				(font
					(size 1.27 1.27)
					(thickness 0.15)
				)
				(justify left bottom)
				(hide yes)
			)
		)
		(property "Datasheet" "https://www.bourns.com/docs/product-datasheets/cr.pdf"
			(at 124.46 114.935 0)
			(effects
				(font
					(size 1.27 1.27)
					(thickness 0.15)
				)
				(justify left bottom)
				(hide yes)
			)
		)
		(property "Description" ""
			(at 106.68 94.615 0)
			(effects
				(font
					(size 1.27 1.27)
				)
			)
		)
		(property "Manufacturer" "Bourns"
			(at 129.54 114.935 0)
			(effects
				(font
					(size 1.27 1.27)
					(thickness 0.15)
				)
				(justify left bottom)
				(hide yes)
			)
		)
		(property "MPN" "CR0402-FX-4701GLF"
			(at 127 114.935 0)
			(effects
				(font
					(size 1.27 1.27)
					(thickness 0.15)
				)
				(justify left bottom)
				(hide yes)
			)
		)
		(property "Val" "4k7"
			(at 111.76 99.06 90)
			(effects
				(font
					(size 1.27 1.27)
					(thickness 0.15)
				)
				(justify left bottom)
			)
		)
		(property "License" "Apache-2.0"
			(at 132.08 114.935 0)
			(effects
				(font
					(size 1.27 1.27)
					(thickness 0.15)
				)
				(justify left bottom)
				(hide yes)
			)
		)
		(property "Author" "Antmicro"
			(at 134.62 114.935 0)
			(effects
				(font
					(size 1.27 1.27)
					(thickness 0.15)
				)
				(justify left bottom)
				(hide yes)
			)
		)
		(property "Tolerance" "1%"
			(at 116.84 114.935 0)
			(effects
				(font
					(size 1.27 1.27)
				)
				(justify left bottom)
				(hide yes)
			)
		)
		(pin "1"
		)
		(pin "2"
		)
		(instances
			(project "lpddr4-test-board"
				(path ""
					(reference "R59")
					(unit 1)
				)
			)
		)
	)
	(symbol
		(lib_id "antmicroResistors0402:R_100R_0402")
		(at 92.71 94.615 270)
		(unit 1)
		(exclude_from_sim no)
		(in_bom no)
		(on_board yes)
		(dnp yes)
		(property "Reference" "R54"
			(at 93.98 97.155 90)
			(effects
				(font
					(size 1.27 1.27)
					(thickness 0.15)
				)
				(justify left bottom)
			)
		)
		(property "Value" "R_100R_0402"
			(at 88.9 94.615 0)
			(effects
				(font
					(size 1.27 1.27)
				)
				(justify left bottom)
				(hide yes)
			)
		)
		(property "Footprint" "antmicro-footprints:R_0402_1005Metric"
			(at 77.47 114.935 0)
			(effects
				(font
					(size 1.27 1.27)
					(thickness 0.15)
				)
				(justify left bottom)
				(hide yes)
			)
		)
		(property "Datasheet" "https://www.bourns.com/docs/product-datasheets/cr.pdf"
			(at 74.93 114.935 0)
			(effects
				(font
					(size 1.27 1.27)
					(thickness 0.15)
				)
				(justify left bottom)
				(hide yes)
			)
		)
		(property "Description" ""
			(at 92.71 94.615 0)
			(effects
				(font
					(size 1.27 1.27)
				)
			)
		)
		(property "Manufacturer" "Bourns"
			(at 69.85 114.935 0)
			(effects
				(font
					(size 1.27 1.27)
					(thickness 0.15)
				)
				(justify left bottom)
				(hide yes)
			)
		)
		(property "MPN" "CR0402-FX-1000GLF"
			(at 72.39 114.935 0)
			(effects
				(font
					(size 1.27 1.27)
					(thickness 0.15)
				)
				(justify left bottom)
				(hide yes)
			)
		)
		(property "Val" "100R"
			(at 93.98 99.06 90)
			(effects
				(font
					(size 1.27 1.27)
					(thickness 0.15)
				)
				(justify left bottom)
			)
		)
		(property "License" "Apache-2.0"
			(at 67.31 114.935 0)
			(effects
				(font
					(size 1.27 1.27)
					(thickness 0.15)
				)
				(justify left bottom)
				(hide yes)
			)
		)
		(property "Author" "Antmicro"
			(at 64.77 114.935 0)
			(effects
				(font
					(size 1.27 1.27)
					(thickness 0.15)
				)
				(justify left bottom)
				(hide yes)
			)
		)
		(property "Tolerance" "1%"
			(at 82.55 114.935 0)
			(effects
				(font
					(size 1.27 1.27)
				)
				(justify left bottom)
				(hide yes)
			)
		)
		(pin "1"
		)
		(pin "2"
		)
		(instances
			(project "lpddr4-test-board"
				(path ""
					(reference "R54")
					(unit 1)
				)
			)
		)
	)
	(symbol
		(lib_id "antmicroResistors0402:R_0R_0402")
		(at 220.98 227.965 0)
		(unit 1)
		(exclude_from_sim no)
		(in_bom yes)
		(on_board yes)
		(dnp no)
		(property "Reference" "R62"
			(at 226.06 227.965 0)
			(effects
				(font
					(size 1.27 1.27)
					(thickness 0.15)
				)
				(justify left bottom)
			)
		)
		(property "Value" "R_0R_0402"
			(at 220.98 231.775 0)
			(effects
				(font
					(size 1.27 1.27)
				)
				(justify left bottom)
				(hide yes)
			)
		)
		(property "Footprint" "antmicro-footprints:R_0402_1005Metric"
			(at 241.3 243.205 0)
			(effects
				(font
					(size 1.27 1.27)
					(thickness 0.15)
				)
				(justify left bottom)
				(hide yes)
			)
		)
		(property "Datasheet" "https://industrial.panasonic.com/cdbs/www-data/pdf/RDA0000/AOA0000C301.pdf"
			(at 241.3 245.745 0)
			(effects
				(font
					(size 1.27 1.27)
					(thickness 0.15)
				)
				(justify left bottom)
				(hide yes)
			)
		)
		(property "Description" ""
			(at 220.98 227.965 0)
			(effects
				(font
					(size 1.27 1.27)
				)
			)
		)
		(property "Manufacturer" "Panasonic"
			(at 241.3 250.825 0)
			(effects
				(font
					(size 1.27 1.27)
					(thickness 0.15)
				)
				(justify left bottom)
				(hide yes)
			)
		)
		(property "MPN" "ERJ2GE0R00X"
			(at 241.3 248.285 0)
			(effects
				(font
					(size 1.27 1.27)
					(thickness 0.15)
				)
				(justify left bottom)
				(hide yes)
			)
		)
		(property "Val" "0R"
			(at 217.805 227.965 0)
			(effects
				(font
					(size 1.27 1.27)
					(thickness 0.15)
				)
				(justify left bottom)
			)
		)
		(property "License" "Apache-2.0"
			(at 241.3 253.365 0)
			(effects
				(font
					(size 1.27 1.27)
					(thickness 0.15)
				)
				(justify left bottom)
				(hide yes)
			)
		)
		(property "Author" "Antmicro"
			(at 241.3 255.905 0)
			(effects
				(font
					(size 1.27 1.27)
					(thickness 0.15)
				)
				(justify left bottom)
				(hide yes)
			)
		)
		(property "Tolerance" "~"
			(at 241.3 238.125 0)
			(effects
				(font
					(size 1.27 1.27)
				)
				(justify left bottom)
				(hide yes)
			)
		)
		(property "Current" "1A"
			(at 241.3 258.445 0)
			(effects
				(font
					(size 1.27 1.27)
					(thickness 0.15)
				)
				(justify left bottom)
				(hide yes)
			)
		)
		(pin "1"
		)
		(pin "2"
		)
		(instances
			(project "lpddr4-test-board"
				(path ""
					(reference "R62")
					(unit 1)
				)
			)
		)
	)
	(symbol
		(lib_id "antmicroResistors0402:R_0R_0402")
		(at 220.98 233.045 0)
		(unit 1)
		(exclude_from_sim no)
		(in_bom no)
		(on_board yes)
		(dnp yes)
		(property "Reference" "R63"
			(at 226.06 233.045 0)
			(effects
				(font
					(size 1.27 1.27)
					(thickness 0.15)
				)
				(justify left bottom)
			)
		)
		(property "Value" "R_0R_0402"
			(at 220.98 236.855 0)
			(effects
				(font
					(size 1.27 1.27)
				)
				(justify left bottom)
				(hide yes)
			)
		)
		(property "Footprint" "antmicro-footprints:R_0402_1005Metric"
			(at 241.3 248.285 0)
			(effects
				(font
					(size 1.27 1.27)
					(thickness 0.15)
				)
				(justify left bottom)
				(hide yes)
			)
		)
		(property "Datasheet" "https://industrial.panasonic.com/cdbs/www-data/pdf/RDA0000/AOA0000C301.pdf"
			(at 241.3 250.825 0)
			(effects
				(font
					(size 1.27 1.27)
					(thickness 0.15)
				)
				(justify left bottom)
				(hide yes)
			)
		)
		(property "Description" ""
			(at 220.98 233.045 0)
			(effects
				(font
					(size 1.27 1.27)
				)
			)
		)
		(property "Manufacturer" "Panasonic"
			(at 241.3 255.905 0)
			(effects
				(font
					(size 1.27 1.27)
					(thickness 0.15)
				)
				(justify left bottom)
				(hide yes)
			)
		)
		(property "MPN" "ERJ2GE0R00X"
			(at 241.3 253.365 0)
			(effects
				(font
					(size 1.27 1.27)
					(thickness 0.15)
				)
				(justify left bottom)
				(hide yes)
			)
		)
		(property "Val" "0R"
			(at 217.805 233.045 0)
			(effects
				(font
					(size 1.27 1.27)
					(thickness 0.15)
				)
				(justify left bottom)
			)
		)
		(property "License" "Apache-2.0"
			(at 241.3 258.445 0)
			(effects
				(font
					(size 1.27 1.27)
					(thickness 0.15)
				)
				(justify left bottom)
				(hide yes)
			)
		)
		(property "Author" "Antmicro"
			(at 241.3 260.985 0)
			(effects
				(font
					(size 1.27 1.27)
					(thickness 0.15)
				)
				(justify left bottom)
				(hide yes)
			)
		)
		(property "Tolerance" "~"
			(at 241.3 243.205 0)
			(effects
				(font
					(size 1.27 1.27)
				)
				(justify left bottom)
				(hide yes)
			)
		)
		(property "Current" "1A"
			(at 241.3 263.525 0)
			(effects
				(font
					(size 1.27 1.27)
					(thickness 0.15)
				)
				(justify left bottom)
				(hide yes)
			)
		)
		(pin "1"
		)
		(pin "2"
		)
		(instances
			(project "lpddr4-test-board"
				(path ""
					(reference "R63")
					(unit 1)
				)
			)
		)
	)
	(symbol
		(lib_id "antmicroResistors0402:R_0R_0402")
		(at 220.98 245.11 0)
		(unit 1)
		(exclude_from_sim no)
		(in_bom no)
		(on_board yes)
		(dnp yes)
		(property "Reference" "R64"
			(at 226.06 245.11 0)
			(effects
				(font
					(size 1.27 1.27)
					(thickness 0.15)
				)
				(justify left bottom)
			)
		)
		(property "Value" "R_0R_0402"
			(at 220.98 248.92 0)
			(effects
				(font
					(size 1.27 1.27)
				)
				(justify left bottom)
				(hide yes)
			)
		)
		(property "Footprint" "antmicro-footprints:R_0402_1005Metric"
			(at 241.3 260.35 0)
			(effects
				(font
					(size 1.27 1.27)
					(thickness 0.15)
				)
				(justify left bottom)
				(hide yes)
			)
		)
		(property "Datasheet" "https://industrial.panasonic.com/cdbs/www-data/pdf/RDA0000/AOA0000C301.pdf"
			(at 241.3 262.89 0)
			(effects
				(font
					(size 1.27 1.27)
					(thickness 0.15)
				)
				(justify left bottom)
				(hide yes)
			)
		)
		(property "Description" ""
			(at 220.98 245.11 0)
			(effects
				(font
					(size 1.27 1.27)
				)
			)
		)
		(property "Manufacturer" "Panasonic"
			(at 241.3 267.97 0)
			(effects
				(font
					(size 1.27 1.27)
					(thickness 0.15)
				)
				(justify left bottom)
				(hide yes)
			)
		)
		(property "MPN" "ERJ2GE0R00X"
			(at 241.3 265.43 0)
			(effects
				(font
					(size 1.27 1.27)
					(thickness 0.15)
				)
				(justify left bottom)
				(hide yes)
			)
		)
		(property "Val" "0R"
			(at 217.805 245.11 0)
			(effects
				(font
					(size 1.27 1.27)
					(thickness 0.15)
				)
				(justify left bottom)
			)
		)
		(property "License" "Apache-2.0"
			(at 241.3 270.51 0)
			(effects
				(font
					(size 1.27 1.27)
					(thickness 0.15)
				)
				(justify left bottom)
				(hide yes)
			)
		)
		(property "Author" "Antmicro"
			(at 241.3 273.05 0)
			(effects
				(font
					(size 1.27 1.27)
					(thickness 0.15)
				)
				(justify left bottom)
				(hide yes)
			)
		)
		(property "Tolerance" "~"
			(at 241.3 255.27 0)
			(effects
				(font
					(size 1.27 1.27)
				)
				(justify left bottom)
				(hide yes)
			)
		)
		(property "Current" "1A"
			(at 241.3 275.59 0)
			(effects
				(font
					(size 1.27 1.27)
					(thickness 0.15)
				)
				(justify left bottom)
				(hide yes)
			)
		)
		(pin "1"
		)
		(pin "2"
		)
		(instances
			(project "lpddr4-test-board"
				(path ""
					(reference "R64")
					(unit 1)
				)
			)
		)
	)
	(symbol
		(lib_id "antmicroResistors0402:R_0R_0402")
		(at 220.98 250.19 0)
		(unit 1)
		(exclude_from_sim no)
		(in_bom yes)
		(on_board yes)
		(dnp no)
		(property "Reference" "R65"
			(at 226.06 250.19 0)
			(effects
				(font
					(size 1.27 1.27)
					(thickness 0.15)
				)
				(justify left bottom)
			)
		)
		(property "Value" "R_0R_0402"
			(at 220.98 254 0)
			(effects
				(font
					(size 1.27 1.27)
				)
				(justify left bottom)
				(hide yes)
			)
		)
		(property "Footprint" "antmicro-footprints:R_0402_1005Metric"
			(at 241.3 265.43 0)
			(effects
				(font
					(size 1.27 1.27)
					(thickness 0.15)
				)
				(justify left bottom)
				(hide yes)
			)
		)
		(property "Datasheet" "https://industrial.panasonic.com/cdbs/www-data/pdf/RDA0000/AOA0000C301.pdf"
			(at 241.3 267.97 0)
			(effects
				(font
					(size 1.27 1.27)
					(thickness 0.15)
				)
				(justify left bottom)
				(hide yes)
			)
		)
		(property "Description" ""
			(at 220.98 250.19 0)
			(effects
				(font
					(size 1.27 1.27)
				)
			)
		)
		(property "Manufacturer" "Panasonic"
			(at 241.3 273.05 0)
			(effects
				(font
					(size 1.27 1.27)
					(thickness 0.15)
				)
				(justify left bottom)
				(hide yes)
			)
		)
		(property "MPN" "ERJ2GE0R00X"
			(at 241.3 270.51 0)
			(effects
				(font
					(size 1.27 1.27)
					(thickness 0.15)
				)
				(justify left bottom)
				(hide yes)
			)
		)
		(property "Val" "0R"
			(at 217.805 250.19 0)
			(effects
				(font
					(size 1.27 1.27)
					(thickness 0.15)
				)
				(justify left bottom)
			)
		)
		(property "License" "Apache-2.0"
			(at 241.3 275.59 0)
			(effects
				(font
					(size 1.27 1.27)
					(thickness 0.15)
				)
				(justify left bottom)
				(hide yes)
			)
		)
		(property "Author" "Antmicro"
			(at 241.3 278.13 0)
			(effects
				(font
					(size 1.27 1.27)
					(thickness 0.15)
				)
				(justify left bottom)
				(hide yes)
			)
		)
		(property "Tolerance" "~"
			(at 241.3 260.35 0)
			(effects
				(font
					(size 1.27 1.27)
				)
				(justify left bottom)
				(hide yes)
			)
		)
		(property "Current" "1A"
			(at 241.3 280.67 0)
			(effects
				(font
					(size 1.27 1.27)
					(thickness 0.15)
				)
				(justify left bottom)
				(hide yes)
			)
		)
		(pin "1"
		)
		(pin "2"
		)
		(instances
			(project "lpddr4-test-board"
				(path ""
					(reference "R65")
					(unit 1)
				)
			)
		)
	)
	(symbol
		(lib_id "antmicroResistors0402:R_2k2_0402")
		(at 86.36 89.535 270)
		(unit 1)
		(exclude_from_sim no)
		(in_bom yes)
		(on_board yes)
		(dnp no)
		(property "Reference" "R53"
			(at 87.63 92.075 90)
			(effects
				(font
					(size 1.27 1.27)
					(thickness 0.15)
				)
				(justify left bottom)
			)
		)
		(property "Value" "R_2k2_0402"
			(at 82.55 89.535 0)
			(effects
				(font
					(size 1.27 1.27)
				)
				(justify left bottom)
				(hide yes)
			)
		)
		(property "Footprint" "antmicro-footprints:R_0402_1005Metric"
			(at 71.12 109.855 0)
			(effects
				(font
					(size 1.27 1.27)
					(thickness 0.15)
				)
				(justify left bottom)
				(hide yes)
			)
		)
		(property "Datasheet" "https://www.bourns.com/docs/product-datasheets/cr.pdf"
			(at 68.58 109.855 0)
			(effects
				(font
					(size 1.27 1.27)
					(thickness 0.15)
				)
				(justify left bottom)
				(hide yes)
			)
		)
		(property "Description" ""
			(at 86.36 89.535 0)
			(effects
				(font
					(size 1.27 1.27)
				)
			)
		)
		(property "Manufacturer" "Bourns"
			(at 63.5 109.855 0)
			(effects
				(font
					(size 1.27 1.27)
					(thickness 0.15)
				)
				(justify left bottom)
				(hide yes)
			)
		)
		(property "MPN" "CR0402-FX-2201GLF"
			(at 66.04 109.855 0)
			(effects
				(font
					(size 1.27 1.27)
					(thickness 0.15)
				)
				(justify left bottom)
				(hide yes)
			)
		)
		(property "Val" "2k2"
			(at 87.63 93.98 90)
			(effects
				(font
					(size 1.27 1.27)
					(thickness 0.15)
				)
				(justify left bottom)
			)
		)
		(property "License" "Apache-2.0"
			(at 60.96 109.855 0)
			(effects
				(font
					(size 1.27 1.27)
					(thickness 0.15)
				)
				(justify left bottom)
				(hide yes)
			)
		)
		(property "Author" "Antmicro"
			(at 58.42 109.855 0)
			(effects
				(font
					(size 1.27 1.27)
					(thickness 0.15)
				)
				(justify left bottom)
				(hide yes)
			)
		)
		(property "Tolerance" "1%"
			(at 76.2 109.855 0)
			(effects
				(font
					(size 1.27 1.27)
				)
				(justify left bottom)
				(hide yes)
			)
		)
		(pin "1"
		)
		(pin "2"
		)
		(instances
			(project "lpddr4-test-board"
				(path ""
					(reference "R53")
					(unit 1)
				)
			)
		)
	)
	(symbol
		(lib_id "antmicroGenericPinHeaders:PinHeader_2x7_P2mm_Drill0.9mm_878311420")
		(at 31.75 233.68 0)
		(unit 1)
		(exclude_from_sim no)
		(in_bom yes)
		(on_board yes)
		(dnp no)
		(fields_autoplaced yes)
		(property "Reference" "J4"
			(at 36.83 227.33 0)
			(effects
				(font
					(size 1.27 1.27)
					(thickness 0.15)
				)
			)
		)
		(property "Value" "PinHeader_2x7_P2mm_Drill1mm_Shrouded"
			(at 36.83 226.695 0)
			(effects
				(font
					(size 1.27 1.27)
				)
				(hide yes)
			)
		)
		(property "Footprint" "antmicro-footprints:PinHeader_2x7_P2mm_Drill0.9mm_878311420"
			(at 57.15 241.3 0)
			(effects
				(font
					(size 1.27 1.27)
					(thickness 0.15)
				)
				(justify left bottom)
				(hide yes)
			)
		)
		(property "Datasheet" "https://www.molex.com/en-us/products/part-detail-pdf/878311420?display=pdf"
			(at 57.15 243.84 0)
			(effects
				(font
					(size 1.27 1.27)
					(thickness 0.15)
				)
				(justify left bottom)
				(hide yes)
			)
		)
		(property "Description" "2.00mm Pitch, Milli-Grid PCB Header, Dual Row, Vertical, Through Hole, Shrouded, 14 Circuits, 0.38µm Gold (Au) Plating, with Center Polarization Slot, with Locking Window, without PCB Locator, Tube"
			(at 57.15 256.54 0)
			(effects
				(font
					(size 1.27 1.27)
				)
				(justify left bottom)
				(hide yes)
			)
		)
		(property "MPN" "878311420"
			(at 36.83 229.87 0)
			(effects
				(font
					(size 1.27 1.27)
					(thickness 0.15)
				)
			)
		)
		(property "Manufacturer" "Molex"
			(at 57.15 248.92 0)
			(effects
				(font
					(size 1.27 1.27)
					(thickness 0.15)
				)
				(justify left bottom)
				(hide yes)
			)
		)
		(property "Author" "Antmicro"
			(at 57.15 251.46 0)
			(effects
				(font
					(size 1.27 1.27)
					(thickness 0.15)
				)
				(justify left bottom)
				(hide yes)
			)
		)
		(property "License" "Apache-2.0"
			(at 57.15 254 0)
			(effects
				(font
					(size 1.27 1.27)
					(thickness 0.15)
				)
				(justify left bottom)
				(hide yes)
			)
		)
		(pin "1"
		)
		(pin "10"
		)
		(pin "11"
		)
		(pin "12"
		)
		(pin "13"
		)
		(pin "14"
		)
		(pin "2"
		)
		(pin "3"
		)
		(pin "4"
		)
		(pin "5"
		)
		(pin "6"
		)
		(pin "7"
		)
		(pin "8"
		)
		(pin "9"
		)
		(instances
			(project "lpddr4-test-board"
				(path ""
					(reference "J4")
					(unit 1)
				)
			)
		)
	)
	(symbol
		(lib_id "antmicropower:GND")
		(at 317.5 159.385 0)
		(unit 1)
		(exclude_from_sim no)
		(in_bom yes)
		(on_board yes)
		(dnp no)
		(property "Reference" "#PWR057"
			(at 326.39 161.925 0)
			(effects
				(font
					(size 1.27 1.27)
					(thickness 0.15)
				)
				(justify left bottom)
				(hide yes)
			)
		)
		(property "Value" "GND"
			(at 315.595 163.83 0)
			(effects
				(font
					(size 1.27 1.27)
				)
				(justify left bottom)
			)
		)
		(property "Footprint" ""
			(at 326.39 167.005 0)
			(effects
				(font
					(size 1.27 1.27)
					(thickness 0.15)
				)
				(justify left bottom)
				(hide yes)
			)
		)
		(property "Datasheet" ""
			(at 326.39 172.085 0)
			(effects
				(font
					(size 1.27 1.27)
					(thickness 0.15)
				)
				(justify left bottom)
				(hide yes)
			)
		)
		(property "Description" ""
			(at 317.5 159.385 0)
			(effects
				(font
					(size 1.27 1.27)
				)
			)
		)
		(property "Author" "Antmicro"
			(at 326.39 167.005 0)
			(effects
				(font
					(size 1.27 1.27)
					(thickness 0.15)
				)
				(justify left bottom)
				(hide yes)
			)
		)
		(property "License" "Apache-2.0"
			(at 326.39 169.545 0)
			(effects
				(font
					(size 1.27 1.27)
					(thickness 0.15)
				)
				(justify left bottom)
				(hide yes)
			)
		)
		(pin "1"
		)
		(instances
			(project "lpddr4-test-board"
				(path ""
					(reference "#PWR057")
					(unit 1)
				)
			)
		)
	)
	(symbol
		(lib_id "antmicroResistors0402:R_4k7_0402")
		(at 280.67 113.03 270)
		(unit 1)
		(exclude_from_sim no)
		(in_bom yes)
		(on_board yes)
		(dnp no)
		(property "Reference" "R66"
			(at 281.94 115.57 90)
			(effects
				(font
					(size 1.27 1.27)
					(thickness 0.15)
				)
				(justify left bottom)
			)
		)
		(property "Value" "R_4k7_0402"
			(at 276.86 113.03 0)
			(effects
				(font
					(size 1.27 1.27)
				)
				(justify left bottom)
				(hide yes)
			)
		)
		(property "Footprint" "antmicro-footprints:R_0402_1005Metric"
			(at 265.43 133.35 0)
			(effects
				(font
					(size 1.27 1.27)
					(thickness 0.15)
				)
				(justify left bottom)
				(hide yes)
			)
		)
		(property "Datasheet" "https://www.bourns.com/docs/product-datasheets/cr.pdf"
			(at 262.89 133.35 0)
			(effects
				(font
					(size 1.27 1.27)
					(thickness 0.15)
				)
				(justify left bottom)
				(hide yes)
			)
		)
		(property "Description" ""
			(at 280.67 113.03 0)
			(effects
				(font
					(size 1.27 1.27)
				)
			)
		)
		(property "Manufacturer" "Bourns"
			(at 257.81 133.35 0)
			(effects
				(font
					(size 1.27 1.27)
					(thickness 0.15)
				)
				(justify left bottom)
				(hide yes)
			)
		)
		(property "MPN" "CR0402-FX-4701GLF"
			(at 260.35 133.35 0)
			(effects
				(font
					(size 1.27 1.27)
					(thickness 0.15)
				)
				(justify left bottom)
				(hide yes)
			)
		)
		(property "Val" "4k7"
			(at 281.94 117.4751 90)
			(effects
				(font
					(size 1.27 1.27)
					(thickness 0.15)
				)
				(justify left bottom)
			)
		)
		(property "License" "Apache-2.0"
			(at 255.27 133.35 0)
			(effects
				(font
					(size 1.27 1.27)
					(thickness 0.15)
				)
				(justify left bottom)
				(hide yes)
			)
		)
		(property "Author" "Antmicro"
			(at 252.73 133.35 0)
			(effects
				(font
					(size 1.27 1.27)
					(thickness 0.15)
				)
				(justify left bottom)
				(hide yes)
			)
		)
		(property "Tolerance" "1%"
			(at 270.51 133.35 0)
			(effects
				(font
					(size 1.27 1.27)
				)
				(justify left bottom)
				(hide yes)
			)
		)
		(pin "1"
		)
		(pin "2"
		)
		(instances
			(project "lpddr4-test-board"
				(path ""
					(reference "R66")
					(unit 1)
				)
			)
		)
	)
	(symbol
		(lib_id "antmicropower:GND")
		(at 92.71 127.635 0)
		(unit 1)
		(exclude_from_sim no)
		(in_bom yes)
		(on_board yes)
		(dnp no)
		(property "Reference" "#PWR049"
			(at 101.6 130.175 0)
			(effects
				(font
					(size 1.27 1.27)
					(thickness 0.15)
				)
				(justify left bottom)
				(hide yes)
			)
		)
		(property "Value" "GND"
			(at 90.805 132.08 0)
			(effects
				(font
					(size 1.27 1.27)
				)
				(justify left bottom)
			)
		)
		(property "Footprint" ""
			(at 101.6 135.255 0)
			(effects
				(font
					(size 1.27 1.27)
					(thickness 0.15)
				)
				(justify left bottom)
				(hide yes)
			)
		)
		(property "Datasheet" ""
			(at 101.6 140.335 0)
			(effects
				(font
					(size 1.27 1.27)
					(thickness 0.15)
				)
				(justify left bottom)
				(hide yes)
			)
		)
		(property "Description" ""
			(at 92.71 127.635 0)
			(effects
				(font
					(size 1.27 1.27)
				)
			)
		)
		(property "Author" "Antmicro"
			(at 101.6 135.255 0)
			(effects
				(font
					(size 1.27 1.27)
					(thickness 0.15)
				)
				(justify left bottom)
				(hide yes)
			)
		)
		(property "License" "Apache-2.0"
			(at 101.6 137.795 0)
			(effects
				(font
					(size 1.27 1.27)
					(thickness 0.15)
				)
				(justify left bottom)
				(hide yes)
			)
		)
		(pin "1"
		)
		(instances
			(project "lpddr4-test-board"
				(path ""
					(reference "#PWR049")
					(unit 1)
				)
			)
		)
	)
	(symbol
		(lib_id "antmicroCapacitorsmisc:C_100n_6V3_0402")
		(at 48.26 113.665 270)
		(mirror x)
		(unit 1)
		(exclude_from_sim no)
		(in_bom yes)
		(on_board yes)
		(dnp no)
		(property "Reference" "C22"
			(at 48.895 110.49 90)
			(effects
				(font
					(size 1.27 1.27)
					(thickness 0.15)
				)
				(justify left top)
			)
		)
		(property "Value" "C_100n_6V3_0402"
			(at 44.45 113.665 0)
			(effects
				(font
					(size 1.27 1.27)
				)
				(justify left bottom)
				(hide yes)
			)
		)
		(property "Footprint" "antmicro-footprints:C_0402_1005Metric"
			(at 35.56 93.345 0)
			(effects
				(font
					(size 1.27 1.27)
					(thickness 0.15)
				)
				(justify left bottom)
				(hide yes)
			)
		)
		(property "Datasheet" " "
			(at 33.02 93.345 0)
			(effects
				(font
					(size 1.27 1.27)
					(thickness 0.15)
				)
				(justify left bottom)
				(hide yes)
			)
		)
		(property "Description" ""
			(at 48.26 113.665 0)
			(effects
				(font
					(size 1.27 1.27)
				)
			)
		)
		(property "Manufacturer" "Walsin"
			(at 27.94 93.345 0)
			(effects
				(font
					(size 1.27 1.27)
					(thickness 0.15)
				)
				(justify left bottom)
				(hide yes)
			)
		)
		(property "MPN" "0402X104K6R3CT"
			(at 30.48 93.345 0)
			(effects
				(font
					(size 1.27 1.27)
					(thickness 0.15)
				)
				(justify left bottom)
				(hide yes)
			)
		)
		(property "Val" "100n"
			(at 48.895 114.3 90)
			(effects
				(font
					(size 1.27 1.27)
					(thickness 0.15)
				)
				(justify left top)
			)
		)
		(property "License" "Apache-2.0"
			(at 25.4 93.345 0)
			(effects
				(font
					(size 1.27 1.27)
					(thickness 0.15)
				)
				(justify left bottom)
				(hide yes)
			)
		)
		(property "Author" "Antmicro"
			(at 22.86 93.345 0)
			(effects
				(font
					(size 1.27 1.27)
					(thickness 0.15)
				)
				(justify left bottom)
				(hide yes)
			)
		)
		(property "Voltage" ""
			(at 20.32 93.345 0)
			(effects
				(font
					(size 1.27 1.27)
				)
				(justify left bottom)
				(hide yes)
			)
		)
		(property "Dielectric" ""
			(at 17.78 93.345 0)
			(effects
				(font
					(size 1.27 1.27)
				)
				(justify left bottom)
				(hide yes)
			)
		)
		(pin "1"
		)
		(pin "2"
		)
		(instances
			(project "lpddr4-test-board"
				(path ""
					(reference "C22")
					(unit 1)
				)
			)
		)
	)
	(symbol
		(lib_id "antmicropower:GND")
		(at 228.6 251.46 0)
		(unit 1)
		(exclude_from_sim no)
		(in_bom yes)
		(on_board yes)
		(dnp no)
		(property "Reference" "#PWR0129"
			(at 237.49 254 0)
			(effects
				(font
					(size 1.27 1.27)
					(thickness 0.15)
				)
				(justify left bottom)
				(hide yes)
			)
		)
		(property "Value" "GND"
			(at 226.695 255.905 0)
			(effects
				(font
					(size 1.27 1.27)
				)
				(justify left bottom)
			)
		)
		(property "Footprint" ""
			(at 237.49 259.08 0)
			(effects
				(font
					(size 1.27 1.27)
					(thickness 0.15)
				)
				(justify left bottom)
				(hide yes)
			)
		)
		(property "Datasheet" ""
			(at 237.49 264.16 0)
			(effects
				(font
					(size 1.27 1.27)
					(thickness 0.15)
				)
				(justify left bottom)
				(hide yes)
			)
		)
		(property "Description" ""
			(at 228.6 251.46 0)
			(effects
				(font
					(size 1.27 1.27)
				)
			)
		)
		(property "Author" "Antmicro"
			(at 237.49 259.08 0)
			(effects
				(font
					(size 1.27 1.27)
					(thickness 0.15)
				)
				(justify left bottom)
				(hide yes)
			)
		)
		(property "License" "Apache-2.0"
			(at 237.49 261.62 0)
			(effects
				(font
					(size 1.27 1.27)
					(thickness 0.15)
				)
				(justify left bottom)
				(hide yes)
			)
		)
		(pin "1"
		)
		(instances
			(project "lpddr4-test-board"
				(path ""
					(reference "#PWR0129")
					(unit 1)
				)
			)
		)
	)
	(symbol
		(lib_id "antmicroFPGAChips:XC7K70T-FBG484")
		(at 320.04 98.425 0)
		(unit 2)
		(exclude_from_sim no)
		(in_bom yes)
		(on_board yes)
		(dnp no)
		(property "Reference" "U3"
			(at 325.12 90.17 0)
			(effects
				(font
					(size 1.27 1.27)
					(thickness 0.15)
				)
				(justify left bottom)
			)
		)
		(property "Value" "XC7K70T-FBG484"
			(at 373.38 103.505 0)
			(effects
				(font
					(size 1.27 1.27)
					(thickness 0.15)
				)
				(justify left bottom)
				(hide yes)
			)
		)
		(property "Footprint" "antmicro-footprints:BGA-484_23x23mm_Layout22x22_P1mm_FBG484"
			(at 373.38 106.045 0)
			(effects
				(font
					(size 1.27 1.27)
					(thickness 0.15)
				)
				(justify left bottom)
				(hide yes)
			)
		)
		(property "Datasheet" "https://docs.xilinx.com/v/u/en-US/ds182_Kintex_7_Data_Sheet"
			(at 373.38 108.585 0)
			(effects
				(font
					(size 1.27 1.27)
					(thickness 0.15)
				)
				(justify left bottom)
				(hide yes)
			)
		)
		(property "Description" ""
			(at 320.04 98.425 0)
			(effects
				(font
					(size 1.27 1.27)
				)
			)
		)
		(property "Manufacturer" "AMD-Xilinx"
			(at 373.38 111.125 0)
			(effects
				(font
					(size 1.27 1.27)
					(thickness 0.15)
				)
				(justify left bottom)
				(hide yes)
			)
		)
		(property "MPN" "XC7K70T-1FBG484C"
			(at 325.12 92.71 0)
			(effects
				(font
					(size 1.27 1.27)
					(thickness 0.15)
				)
				(justify left bottom)
			)
		)
		(property "Author" "Antmicro"
			(at 373.38 113.665 0)
			(effects
				(font
					(size 1.27 1.27)
					(thickness 0.15)
				)
				(justify left bottom)
				(hide yes)
			)
		)
		(property "License" "Apache-2.0"
			(at 373.38 116.205 0)
			(effects
				(font
					(size 1.27 1.27)
					(thickness 0.15)
				)
				(justify left bottom)
				(hide yes)
			)
		)
		(pin "G7"
		)
		(pin "H6"
		)
		(pin "H7"
		)
		(pin "J5"
		)
		(pin "J6"
		)
		(pin "K6"
		)
		(pin "K7"
		)
		(pin "L11"
		)
		(pin "L12"
		)
		(pin "L6"
		)
		(pin "L7"
		)
		(pin "M11"
		)
		(pin "M12"
		)
		(pin "M6"
		)
		(pin "M7"
		)
		(pin "N11"
		)
		(pin "N12"
		)
		(pin "P6"
		)
		(pin "A1"
		)
		(pin "A12"
		)
		(pin "A17"
		)
		(pin "A2"
		)
		(pin "A22"
		)
		(pin "A5"
		)
		(pin "A6"
		)
		(pin "A7"
		)
		(pin "AA12"
		)
		(pin "AA17"
		)
		(pin "AA2"
		)
		(pin "AA22"
		)
		(pin "AA7"
		)
		(pin "AB14"
		)
		(pin "AB19"
		)
		(pin "AB4"
		)
		(pin "AB9"
		)
		(pin "B14"
		)
		(pin "B19"
		)
		(pin "B3"
		)
		(pin "B4"
		)
		(pin "B7"
		)
		(pin "B9"
		)
		(pin "C1"
		)
		(pin "C11"
		)
		(pin "C16"
		)
		(pin "C2"
		)
		(pin "C21"
		)
		(pin "C5"
		)
		(pin "C6"
		)
		(pin "C7"
		)
		(pin "D13"
		)
		(pin "D18"
		)
		(pin "D3"
		)
		(pin "D4"
		)
		(pin "D7"
		)
		(pin "D8"
		)
		(pin "E1"
		)
		(pin "E10"
		)
		(pin "E15"
		)
		(pin "E2"
		)
		(pin "E20"
		)
		(pin "E5"
		)
		(pin "E6"
		)
		(pin "E7"
		)
		(pin "F12"
		)
		(pin "F17"
		)
		(pin "F22"
		)
		(pin "F3"
		)
		(pin "F4"
		)
		(pin "F7"
		)
		(pin "G1"
		)
		(pin "G14"
		)
		(pin "G19"
		)
		(pin "G2"
		)
		(pin "G5"
		)
		(pin "G6"
		)
		(pin "G9"
		)
		(pin "H1"
		)
		(pin "H11"
		)
		(pin "H16"
		)
		(pin "H2"
		)
		(pin "H21"
		)
		(pin "H3"
		)
		(pin "H4"
		)
		(pin "H5"
		)
		(pin "J1"
		)
		(pin "J10"
		)
		(pin "J11"
		)
		(pin "J12"
		)
		(pin "J13"
		)
		(pin "J14"
		)
		(pin "J15"
		)
		(pin "J18"
		)
		(pin "J2"
		)
		(pin "J3"
		)
		(pin "J4"
		)
		(pin "J7"
		)
		(pin "J8"
		)
		(pin "J9"
		)
		(pin "K10"
		)
		(pin "K11"
		)
		(pin "K12"
		)
		(pin "K13"
		)
		(pin "K14"
		)
		(pin "K15"
		)
		(pin "K20"
		)
		(pin "K5"
		)
		(pin "K8"
		)
		(pin "K9"
		)
		(pin "L10"
		)
		(pin "L13"
		)
		(pin "L14"
		)
		(pin "L15"
		)
		(pin "L17"
		)
		(pin "L2"
		)
		(pin "L22"
		)
		(pin "L8"
		)
		(pin "L9"
		)
		(pin "M10"
		)
		(pin "M13"
		)
		(pin "M14"
		)
		(pin "M15"
		)
		(pin "M19"
		)
		(pin "M4"
		)
		(pin "M8"
		)
		(pin "M9"
		)
		(pin "N1"
		)
		(pin "N10"
		)
		(pin "N13"
		)
		(pin "N14"
		)
		(pin "N15"
		)
		(pin "N16"
		)
		(pin "N21"
		)
		(pin "N6"
		)
		(pin "N7"
		)
		(pin "N8"
		)
		(pin "N9"
		)
		(pin "P10"
		)
		(pin "P11"
		)
		(pin "P12"
		)
		(pin "P13"
		)
		(pin "P14"
		)
		(pin "P15"
		)
		(pin "P18"
		)
		(pin "P3"
		)
		(pin "P7"
		)
		(pin "P8"
		)
		(pin "P9"
		)
		(pin "AB11"
		)
		(pin "AB12"
		)
		(pin "AB13"
		)
		(pin "AB5"
		)
		(pin "AB6"
		)
		(pin "R10"
		)
		(pin "R11"
		)
		(pin "R12"
		)
		(pin "R13"
		)
		(pin "R14"
		)
		(pin "R15"
		)
		(pin "R20"
		)
		(pin "R5"
		)
		(pin "R8"
		)
		(pin "R9"
		)
		(pin "T12"
		)
		(pin "T17"
		)
		(pin "T2"
		)
		(pin "T22"
		)
		(pin "T7"
		)
		(pin "U14"
		)
		(pin "U19"
		)
		(pin "U4"
		)
		(pin "U9"
		)
		(pin "V1"
		)
		(pin "V11"
		)
		(pin "V16"
		)
		(pin "V21"
		)
		(pin "V6"
		)
		(pin "W13"
		)
		(pin "W18"
		)
		(pin "W3"
		)
		(pin "W8"
		)
		(pin "Y10"
		)
		(pin "Y15"
		)
		(pin "Y20"
		)
		(pin "Y5"
		)
		(pin "A3"
		)
		(pin "A4"
		)
		(pin "B1"
		)
		(pin "B2"
		)
		(pin "B5"
		)
		(pin "B6"
		)
		(pin "C3"
		)
		(pin "C4"
		)
		(pin "D1"
		)
		(pin "D2"
		)
		(pin "D5"
		)
		(pin "D6"
		)
		(pin "E3"
		)
		(pin "E4"
		)
		(pin "F1"
		)
		(pin "F2"
		)
		(pin "F5"
		)
		(pin "F6"
		)
		(pin "G3"
		)
		(pin "G4"
		)
		(pin "AA1"
		)
		(pin "AA3"
		)
		(pin "AA4"
		)
		(pin "AB1"
		)
		(pin "AB2"
		)
		(pin "AB3"
		)
		(pin "K1"
		)
		(pin "K2"
		)
		(pin "K3"
		)
		(pin "K4"
		)
		(pin "L1"
		)
		(pin "L3"
		)
		(pin "L4"
		)
		(pin "L5"
		)
		(pin "M1"
		)
		(pin "M2"
		)
		(pin "M3"
		)
		(pin "M5"
		)
		(pin "N2"
		)
		(pin "N3"
		)
		(pin "N4"
		)
		(pin "N5"
		)
		(pin "P1"
		)
		(pin "P2"
		)
		(pin "P4"
		)
		(pin "P5"
		)
		(pin "R1"
		)
		(pin "R2"
		)
		(pin "R3"
		)
		(pin "R4"
		)
		(pin "T1"
		)
		(pin "T3"
		)
		(pin "T4"
		)
		(pin "T5"
		)
		(pin "U1"
		)
		(pin "U2"
		)
		(pin "U3"
		)
		(pin "U5"
		)
		(pin "V2"
		)
		(pin "V3"
		)
		(pin "V4"
		)
		(pin "V5"
		)
		(pin "W1"
		)
		(pin "W2"
		)
		(pin "W4"
		)
		(pin "W5"
		)
		(pin "Y1"
		)
		(pin "Y2"
		)
		(pin "Y3"
		)
		(pin "Y4"
		)
		(pin "AA10"
		)
		(pin "AA11"
		)
		(pin "AA13"
		)
		(pin "AA5"
		)
		(pin "AA6"
		)
		(pin "AA8"
		)
		(pin "AA9"
		)
		(pin "AB10"
		)
		(pin "AB7"
		)
		(pin "AB8"
		)
		(pin "R6"
		)
		(pin "R7"
		)
		(pin "T10"
		)
		(pin "T11"
		)
		(pin "T13"
		)
		(pin "T14"
		)
		(pin "T6"
		)
		(pin "T8"
		)
		(pin "T9"
		)
		(pin "U10"
		)
		(pin "U11"
		)
		(pin "U12"
		)
		(pin "U13"
		)
		(pin "U6"
		)
		(pin "U7"
		)
		(pin "U8"
		)
		(pin "V10"
		)
		(pin "V12"
		)
		(pin "V13"
		)
		(pin "V7"
		)
		(pin "V8"
		)
		(pin "V9"
		)
		(pin "W10"
		)
		(pin "W11"
		)
		(pin "W12"
		)
		(pin "W6"
		)
		(pin "W7"
		)
		(pin "W9"
		)
		(pin "Y11"
		)
		(pin "Y12"
		)
		(pin "Y13"
		)
		(pin "Y6"
		)
		(pin "Y7"
		)
		(pin "Y8"
		)
		(pin "Y9"
		)
		(pin "A10"
		)
		(pin "A11"
		)
		(pin "A8"
		)
		(pin "A9"
		)
		(pin "B10"
		)
		(pin "B11"
		)
		(pin "B8"
		)
		(pin "C10"
		)
		(pin "C8"
		)
		(pin "C9"
		)
		(pin "D10"
		)
		(pin "D11"
		)
		(pin "D9"
		)
		(pin "E11"
		)
		(pin "E12"
		)
		(pin "E13"
		)
		(pin "E8"
		)
		(pin "E9"
		)
		(pin "F10"
		)
		(pin "F11"
		)
		(pin "F13"
		)
		(pin "F14"
		)
		(pin "F8"
		)
		(pin "F9"
		)
		(pin "G10"
		)
		(pin "G11"
		)
		(pin "G12"
		)
		(pin "G13"
		)
		(pin "G8"
		)
		(pin "H10"
		)
		(pin "H12"
		)
		(pin "H13"
		)
		(pin "H14"
		)
		(pin "H8"
		)
		(pin "H9"
		)
		(pin "A13"
		)
		(pin "A14"
		)
		(pin "A15"
		)
		(pin "A16"
		)
		(pin "A18"
		)
		(pin "A19"
		)
		(pin "A20"
		)
		(pin "A21"
		)
		(pin "B12"
		)
		(pin "B13"
		)
		(pin "B15"
		)
		(pin "B16"
		)
		(pin "B17"
		)
		(pin "B18"
		)
		(pin "B20"
		)
		(pin "B21"
		)
		(pin "B22"
		)
		(pin "C12"
		)
		(pin "C13"
		)
		(pin "C14"
		)
		(pin "C15"
		)
		(pin "C17"
		)
		(pin "C18"
		)
		(pin "C19"
		)
		(pin "C20"
		)
		(pin "C22"
		)
		(pin "D12"
		)
		(pin "D14"
		)
		(pin "D15"
		)
		(pin "D16"
		)
		(pin "D17"
		)
		(pin "D19"
		)
		(pin "D20"
		)
		(pin "D21"
		)
		(pin "D22"
		)
		(pin "E14"
		)
		(pin "E16"
		)
		(pin "E17"
		)
		(pin "E18"
		)
		(pin "E19"
		)
		(pin "F15"
		)
		(pin "F16"
		)
		(pin "F18"
		)
		(pin "G15"
		)
		(pin "G16"
		)
		(pin "G17"
		)
		(pin "H15"
		)
		(pin "H17"
		)
		(pin "J16"
		)
		(pin "J17"
		)
		(pin "E21"
		)
		(pin "E22"
		)
		(pin "F19"
		)
		(pin "F20"
		)
		(pin "F21"
		)
		(pin "G18"
		)
		(pin "G20"
		)
		(pin "G21"
		)
		(pin "G22"
		)
		(pin "H18"
		)
		(pin "H19"
		)
		(pin "H20"
		)
		(pin "H22"
		)
		(pin "J19"
		)
		(pin "J20"
		)
		(pin "J21"
		)
		(pin "J22"
		)
		(pin "K16"
		)
		(pin "K17"
		)
		(pin "K18"
		)
		(pin "K19"
		)
		(pin "K21"
		)
		(pin "K22"
		)
		(pin "L16"
		)
		(pin "L18"
		)
		(pin "L19"
		)
		(pin "L20"
		)
		(pin "L21"
		)
		(pin "M16"
		)
		(pin "M17"
		)
		(pin "M18"
		)
		(pin "M20"
		)
		(pin "M21"
		)
		(pin "M22"
		)
		(pin "N17"
		)
		(pin "N18"
		)
		(pin "N19"
		)
		(pin "N20"
		)
		(pin "N22"
		)
		(pin "P16"
		)
		(pin "P17"
		)
		(pin "P19"
		)
		(pin "P20"
		)
		(pin "P21"
		)
		(pin "P22"
		)
		(pin "R17"
		)
		(pin "R18"
		)
		(pin "R19"
		)
		(pin "R21"
		)
		(pin "R22"
		)
		(pin "AA14"
		)
		(pin "AA15"
		)
		(pin "AA16"
		)
		(pin "AA18"
		)
		(pin "AA19"
		)
		(pin "AA20"
		)
		(pin "AA21"
		)
		(pin "AB15"
		)
		(pin "AB16"
		)
		(pin "AB17"
		)
		(pin "AB18"
		)
		(pin "AB20"
		)
		(pin "AB21"
		)
		(pin "AB22"
		)
		(pin "R16"
		)
		(pin "T15"
		)
		(pin "T16"
		)
		(pin "T18"
		)
		(pin "T19"
		)
		(pin "T20"
		)
		(pin "T21"
		)
		(pin "U15"
		)
		(pin "U16"
		)
		(pin "U17"
		)
		(pin "U18"
		)
		(pin "U20"
		)
		(pin "U21"
		)
		(pin "U22"
		)
		(pin "V14"
		)
		(pin "V15"
		)
		(pin "V17"
		)
		(pin "V18"
		)
		(pin "V19"
		)
		(pin "V20"
		)
		(pin "V22"
		)
		(pin "W14"
		)
		(pin "W15"
		)
		(pin "W16"
		)
		(pin "W17"
		)
		(pin "W19"
		)
		(pin "W20"
		)
		(pin "W21"
		)
		(pin "W22"
		)
		(pin "Y14"
		)
		(pin "Y16"
		)
		(pin "Y17"
		)
		(pin "Y18"
		)
		(pin "Y19"
		)
		(pin "Y21"
		)
		(pin "Y22"
		)
		(instances
			(project "lpddr4-test-board"
				(path ""
					(reference "U3")
					(unit 2)
				)
			)
		)
	)
	(symbol
		(lib_id "antmicroMemory:S25FL128LAGNFA010")
		(at 71.12 102.235 0)
		(mirror y)
		(unit 1)
		(exclude_from_sim no)
		(in_bom yes)
		(on_board yes)
		(dnp no)
		(property "Reference" "U5"
			(at 59.69 96.52 0)
			(effects
				(font
					(size 1.27 1.27)
				)
				(justify right bottom)
			)
		)
		(property "Value" "S25FL128LAGNFA010"
			(at 30.48 109.855 0)
			(effects
				(font
					(size 1.27 1.27)
					(thickness 0.15)
				)
				(justify left bottom)
				(hide yes)
			)
		)
		(property "Footprint" "antmicro-footprints:WSON-8_6x8x0.5mm_P1.27mm"
			(at 30.48 112.395 0)
			(effects
				(font
					(size 1.27 1.27)
					(thickness 0.15)
				)
				(justify left bottom)
				(hide yes)
			)
		)
		(property "Datasheet" "https://www.infineon.com/dgdl/Infineon-S25FL256L_S25FL128L_256-MB_(32-MB)_128-MB_(16-MB)_3.0_V_FL-L_FLASH_MEMORY-DataSheet-v09_00-EN.pdf?fileId=8ac78c8c7d0d8da4017d0ed40e335224"
			(at 30.48 114.935 0)
			(effects
				(font
					(size 1.27 1.27)
					(thickness 0.15)
				)
				(justify left bottom)
				(hide yes)
			)
		)
		(property "Description" ""
			(at 71.12 102.235 0)
			(effects
				(font
					(size 1.27 1.27)
				)
			)
		)
		(property "Manufacturer" "Cypress Semiconductor"
			(at 30.48 117.475 0)
			(effects
				(font
					(size 1.27 1.27)
					(thickness 0.15)
				)
				(justify left bottom)
				(hide yes)
			)
		)
		(property "MPN" "S25FL128LAGNFA010"
			(at 51.435 99.06 0)
			(effects
				(font
					(size 1.27 1.27)
					(thickness 0.15)
				)
				(justify right bottom)
			)
		)
		(property "Author" "Antmicro"
			(at 30.48 120.015 0)
			(effects
				(font
					(size 1.27 1.27)
					(thickness 0.15)
				)
				(justify left bottom)
				(hide yes)
			)
		)
		(property "License" "Apache-2.0"
			(at 30.48 122.555 0)
			(effects
				(font
					(size 1.27 1.27)
					(thickness 0.15)
				)
				(justify left bottom)
				(hide yes)
			)
		)
		(pin "1"
		)
		(pin "2"
		)
		(pin "3"
		)
		(pin "4"
		)
		(pin "5"
		)
		(pin "6"
		)
		(pin "7"
		)
		(pin "8"
		)
		(pin "9"
		)
		(instances
			(project "lpddr4-test-board"
				(path ""
					(reference "U5")
					(unit 1)
				)
			)
		)
	)
	(symbol
		(lib_id "antmicropower:GND")
		(at 228.6 234.315 0)
		(unit 1)
		(exclude_from_sim no)
		(in_bom yes)
		(on_board yes)
		(dnp no)
		(property "Reference" "#PWR0128"
			(at 237.49 236.855 0)
			(effects
				(font
					(size 1.27 1.27)
					(thickness 0.15)
				)
				(justify left bottom)
				(hide yes)
			)
		)
		(property "Value" "GND"
			(at 226.695 238.76 0)
			(effects
				(font
					(size 1.27 1.27)
				)
				(justify left bottom)
			)
		)
		(property "Footprint" ""
			(at 237.49 241.935 0)
			(effects
				(font
					(size 1.27 1.27)
					(thickness 0.15)
				)
				(justify left bottom)
				(hide yes)
			)
		)
		(property "Datasheet" ""
			(at 237.49 247.015 0)
			(effects
				(font
					(size 1.27 1.27)
					(thickness 0.15)
				)
				(justify left bottom)
				(hide yes)
			)
		)
		(property "Description" ""
			(at 228.6 234.315 0)
			(effects
				(font
					(size 1.27 1.27)
				)
			)
		)
		(property "Author" "Antmicro"
			(at 237.49 241.935 0)
			(effects
				(font
					(size 1.27 1.27)
					(thickness 0.15)
				)
				(justify left bottom)
				(hide yes)
			)
		)
		(property "License" "Apache-2.0"
			(at 237.49 244.475 0)
			(effects
				(font
					(size 1.27 1.27)
					(thickness 0.15)
				)
				(justify left bottom)
				(hide yes)
			)
		)
		(pin "1"
		)
		(instances
			(project "lpddr4-test-board"
				(path ""
					(reference "#PWR0128")
					(unit 1)
				)
			)
		)
	)
	(symbol
		(lib_id "antmicropower:GND")
		(at 160.02 257.175 0)
		(unit 1)
		(exclude_from_sim no)
		(in_bom yes)
		(on_board yes)
		(dnp no)
		(property "Reference" "#PWR0135"
			(at 168.91 259.715 0)
			(effects
				(font
					(size 1.27 1.27)
					(thickness 0.15)
				)
				(justify left bottom)
				(hide yes)
			)
		)
		(property "Value" "GND"
			(at 158.115 261.62 0)
			(effects
				(font
					(size 1.27 1.27)
				)
				(justify left bottom)
			)
		)
		(property "Footprint" ""
			(at 168.91 264.795 0)
			(effects
				(font
					(size 1.27 1.27)
					(thickness 0.15)
				)
				(justify left bottom)
				(hide yes)
			)
		)
		(property "Datasheet" ""
			(at 168.91 269.875 0)
			(effects
				(font
					(size 1.27 1.27)
					(thickness 0.15)
				)
				(justify left bottom)
				(hide yes)
			)
		)
		(property "Description" ""
			(at 160.02 257.175 0)
			(effects
				(font
					(size 1.27 1.27)
				)
			)
		)
		(property "Author" "Antmicro"
			(at 168.91 264.795 0)
			(effects
				(font
					(size 1.27 1.27)
					(thickness 0.15)
				)
				(justify left bottom)
				(hide yes)
			)
		)
		(property "License" "Apache-2.0"
			(at 168.91 267.335 0)
			(effects
				(font
					(size 1.27 1.27)
					(thickness 0.15)
				)
				(justify left bottom)
				(hide yes)
			)
		)
		(pin "1"
		)
		(instances
			(project "lpddr4-test-board"
				(path ""
					(reference "#PWR0135")
					(unit 1)
				)
			)
		)
	)
	(symbol
		(lib_id "antmicropower:GND")
		(at 159.385 237.49 0)
		(unit 1)
		(exclude_from_sim no)
		(in_bom yes)
		(on_board yes)
		(dnp no)
		(property "Reference" "#PWR0136"
			(at 168.275 240.03 0)
			(effects
				(font
					(size 1.27 1.27)
					(thickness 0.15)
				)
				(justify left bottom)
				(hide yes)
			)
		)
		(property "Value" "GND"
			(at 157.48 241.935 0)
			(effects
				(font
					(size 1.27 1.27)
				)
				(justify left bottom)
			)
		)
		(property "Footprint" ""
			(at 168.275 245.11 0)
			(effects
				(font
					(size 1.27 1.27)
					(thickness 0.15)
				)
				(justify left bottom)
				(hide yes)
			)
		)
		(property "Datasheet" ""
			(at 168.275 250.19 0)
			(effects
				(font
					(size 1.27 1.27)
					(thickness 0.15)
				)
				(justify left bottom)
				(hide yes)
			)
		)
		(property "Description" ""
			(at 159.385 237.49 0)
			(effects
				(font
					(size 1.27 1.27)
				)
			)
		)
		(property "Author" "Antmicro"
			(at 168.275 245.11 0)
			(effects
				(font
					(size 1.27 1.27)
					(thickness 0.15)
				)
				(justify left bottom)
				(hide yes)
			)
		)
		(property "License" "Apache-2.0"
			(at 168.275 247.65 0)
			(effects
				(font
					(size 1.27 1.27)
					(thickness 0.15)
				)
				(justify left bottom)
				(hide yes)
			)
		)
		(pin "1"
		)
		(instances
			(project "lpddr4-test-board"
				(path ""
					(reference "#PWR0136")
					(unit 1)
				)
			)
		)
	)
	(symbol
		(lib_id "antmicroTestPoints:TP_1mm_SMD")
		(at 169.545 113.03 180)
		(unit 1)
		(exclude_from_sim no)
		(in_bom yes)
		(on_board yes)
		(dnp no)
		(property "Reference" "TP7"
			(at 161.925 113.665 0)
			(effects
				(font
					(size 1.27 1.27)
					(thickness 0.15)
				)
				(justify right top)
			)
		)
		(property "Value" "TP_1mm_SMD"
			(at 169.545 110.49 0)
			(effects
				(font
					(size 1.27 1.27)
				)
				(justify left bottom)
				(hide yes)
			)
		)
		(property "Footprint" "antmicro-footprints:TP_SMD_1mm"
			(at 154.305 102.87 0)
			(effects
				(font
					(size 1.27 1.27)
					(thickness 0.15)
				)
				(justify left bottom)
				(hide yes)
			)
		)
		(property "Datasheet" ""
			(at 154.305 100.33 0)
			(effects
				(font
					(size 1.27 1.27)
					(thickness 0.15)
				)
				(justify left bottom)
				(hide yes)
			)
		)
		(property "Description" ""
			(at 169.545 113.03 0)
			(effects
				(font
					(size 1.27 1.27)
				)
			)
		)
		(property "MPN" ""
			(at 169.545 113.03 0)
			(effects
				(font
					(size 1.27 1.27)
				)
				(hide yes)
			)
		)
		(property "Manufacturer" ""
			(at 169.545 113.03 0)
			(effects
				(font
					(size 1.27 1.27)
				)
				(hide yes)
			)
		)
		(property "Author" "Antmicro"
			(at 154.305 97.79 0)
			(effects
				(font
					(size 1.27 1.27)
					(thickness 0.15)
				)
				(justify left bottom)
				(hide yes)
			)
		)
		(property "License" "Apache-2.0"
			(at 154.305 95.25 0)
			(effects
				(font
					(size 1.27 1.27)
					(thickness 0.15)
				)
				(justify left bottom)
				(hide yes)
			)
		)
		(pin "1"
		)
		(instances
			(project "lpddr4-test-board"
				(path ""
					(reference "TP7")
					(unit 1)
				)
			)
		)
	)
	(symbol
		(lib_id "antmicroTestPoints:TP_1mm_SMD")
		(at 194.945 113.03 180)
		(unit 1)
		(exclude_from_sim no)
		(in_bom yes)
		(on_board yes)
		(dnp no)
		(property "Reference" "TP8"
			(at 187.325 113.665 0)
			(effects
				(font
					(size 1.27 1.27)
					(thickness 0.15)
				)
				(justify right top)
			)
		)
		(property "Value" "TP_1mm_SMD"
			(at 194.945 110.49 0)
			(effects
				(font
					(size 1.27 1.27)
				)
				(justify left bottom)
				(hide yes)
			)
		)
		(property "Footprint" "antmicro-footprints:TP_SMD_1mm"
			(at 179.705 102.87 0)
			(effects
				(font
					(size 1.27 1.27)
					(thickness 0.15)
				)
				(justify left bottom)
				(hide yes)
			)
		)
		(property "Datasheet" ""
			(at 179.705 100.33 0)
			(effects
				(font
					(size 1.27 1.27)
					(thickness 0.15)
				)
				(justify left bottom)
				(hide yes)
			)
		)
		(property "Description" ""
			(at 194.945 113.03 0)
			(effects
				(font
					(size 1.27 1.27)
				)
			)
		)
		(property "MPN" ""
			(at 194.945 113.03 0)
			(effects
				(font
					(size 1.27 1.27)
				)
				(hide yes)
			)
		)
		(property "Manufacturer" ""
			(at 194.945 113.03 0)
			(effects
				(font
					(size 1.27 1.27)
				)
				(hide yes)
			)
		)
		(property "Author" "Antmicro"
			(at 179.705 97.79 0)
			(effects
				(font
					(size 1.27 1.27)
					(thickness 0.15)
				)
				(justify left bottom)
				(hide yes)
			)
		)
		(property "License" "Apache-2.0"
			(at 179.705 95.25 0)
			(effects
				(font
					(size 1.27 1.27)
					(thickness 0.15)
				)
				(justify left bottom)
				(hide yes)
			)
		)
		(pin "1"
		)
		(instances
			(project "lpddr4-test-board"
				(path ""
					(reference "TP8")
					(unit 1)
				)
			)
		)
	)
	(symbol
		(lib_id "antmicropower:GND")
		(at 217.17 271.145 0)
		(mirror y)
		(unit 1)
		(exclude_from_sim no)
		(in_bom yes)
		(on_board yes)
		(dnp no)
		(property "Reference" "#PWR0125"
			(at 208.28 273.685 0)
			(effects
				(font
					(size 1.27 1.27)
					(thickness 0.15)
				)
				(justify left bottom)
				(hide yes)
			)
		)
		(property "Value" "GND"
			(at 219.075 275.59 0)
			(effects
				(font
					(size 1.27 1.27)
				)
				(justify left bottom)
			)
		)
		(property "Footprint" ""
			(at 208.28 278.765 0)
			(effects
				(font
					(size 1.27 1.27)
					(thickness 0.15)
				)
				(justify left bottom)
				(hide yes)
			)
		)
		(property "Datasheet" ""
			(at 208.28 283.845 0)
			(effects
				(font
					(size 1.27 1.27)
					(thickness 0.15)
				)
				(justify left bottom)
				(hide yes)
			)
		)
		(property "Description" ""
			(at 217.17 271.145 0)
			(effects
				(font
					(size 1.27 1.27)
				)
			)
		)
		(property "Author" "Antmicro"
			(at 208.28 278.765 0)
			(effects
				(font
					(size 1.27 1.27)
					(thickness 0.15)
				)
				(justify left bottom)
				(hide yes)
			)
		)
		(property "License" "Apache-2.0"
			(at 208.28 281.305 0)
			(effects
				(font
					(size 1.27 1.27)
					(thickness 0.15)
				)
				(justify left bottom)
				(hide yes)
			)
		)
		(pin "1"
		)
		(instances
			(project "lpddr4-test-board"
				(path ""
					(reference "#PWR0125")
					(unit 1)
				)
			)
		)
	)
)
